FILE_TYPE = MACRO_DRAWING;
SET COLOR_WIRE YELLOW;
SET COLOR_PROP MONO;
SET COLOR_DOT WHITE;
SET COLOR_ARC YELLOW;
SET COLOR_BODY GREEN;
SET COLOR_NOTE MONO;
SET PROP_DISPLAY VALUE;
SET PAGE_NUMBER P93;
FORCEADD OFFPAGE..5
(1650 775);
FORCEPROP 2 LAST $XR0 93 
J 0
(1426 775);
DISPLAY 0.638298 (1426 775);
PAINT MONO (1426 775);
FORCEPROP 2 LAST PATH I100
J 0
(1700 850);
DISPLAY 1.021277 (1700 850);
PAINT ORANGE (1700 850);
DISPLAY INVISIBLE (1700 850);
FORCEPROP 1 LAST COMMENT_BODY TRUE
J 0
(1750 700);
DISPLAY 0.872340 (1750 700);
PAINT GREEN (1750 700);
DISPLAY INVISIBLE (1750 700);
FORCEPROP 2 LAST CDS_LIB mstr_standard
J 0
(1650 775);
PAINT ORANGE (1650 775);
DISPLAY INVISIBLE (1650 775);
FORCEPROP 1 LAST OFFPAGE TRUE
J 0
(1975 650);
DISPLAY 0.872340 (1975 650);
PAINT GREEN (1975 650);
DISPLAY INVISIBLE (1975 650);
FORCEADD OFFPAGE..4
(1475 3600);
FORCEPROP 2 LAST $XR0 93 
J 0
(1661 3600);
DISPLAY 0.638298 (1661 3600);
PAINT MONO (1661 3600);
FORCEPROP 1 LAST COMMENT_BODY TRUE
J 0
(1450 3500);
DISPLAY 0.872340 (1450 3500);
PAINT GREEN (1450 3500);
DISPLAY INVISIBLE (1450 3500);
FORCEPROP 2 LAST CDS_LIB mstr_standard
J 0
(1475 3600);
PAINT ORANGE (1475 3600);
DISPLAY INVISIBLE (1475 3600);
FORCEPROP 1 LAST OFFPAGE TRUE
J 0
(1800 3475);
DISPLAY 0.872340 (1800 3475);
PAINT GREEN (1800 3475);
DISPLAY INVISIBLE (1800 3475);
FORCEPROP 2 LAST PATH I101
J 0
(1650 3675);
DISPLAY 1.021277 (1650 3675);
PAINT ORANGE (1650 3675);
DISPLAY INVISIBLE (1650 3675);
FORCEADD RES..1
(-825 2175);
FORCEPROP 1 LAST VALUE 0.0
J 2
(-925 2175);
DISPLAY 0.617021 (-925 2175);
PAINT SKYBLUE (-925 2175);
FORCEPROP 1 LAST MATERIAL CHIP
J 0
(-950 2125);
DISPLAY 0.617021 (-950 2125);
PAINT SKYBLUE (-950 2125);
FORCEPROP 1 LASTPIN (-925 2175) $PN 1
J 0
(-913 2187);
DISPLAY 0.617021 (-913 2187);
PAINT ORANGE (-913 2187);
FORCEPROP 1 LAST PART_NUMBER G21497-005
J 0
(-850 2125);
DISPLAY 0.617021 (-850 2125);
PAINT BLUE (-850 2125);
FORCEPROP 1 LAST LOCATION R2T68
J 0
(-875 2225);
DISPLAY 0.617021 (-875 2225);
PAINT AQUA (-875 2225);
FORCEPROP 1 LASTPIN (-725 2175) $PN 2
J 0
(-763 2187);
DISPLAY 0.617021 (-763 2187);
PAINT ORANGE (-763 2187);
FORCEPROP 1 LAST PACK_TYPE 0402
J 0
(-575 2025);
DISPLAY 0.617021 (-575 2025);
PAINT SKYBLUE (-575 2025);
DISPLAY INVISIBLE (-575 2025);
FORCEPROP 1 LAST WATTAGE 1/16W
J 2
(-850 2025);
DISPLAY 0.617021 (-850 2025);
PAINT SKYBLUE (-850 2025);
DISPLAY INVISIBLE (-850 2025);
FORCEPROP 1 LAST TOLERANCE 5%
J 0
(-825 2075);
DISPLAY 0.617021 (-825 2075);
PAINT SKYBLUE (-825 2075);
DISPLAY INVISIBLE (-825 2075);
FORCEPROP 2 LAST CDS_LIB mstr_discrete
J 0
(-825 2175);
PAINT ORANGE (-825 2175);
DISPLAY INVISIBLE (-825 2175);
FORCEPROP 2 LAST SEC_TYPE 0402
J 0
(-875 2375);
DISPLAY 1.021277 (-875 2375);
PAINT ORANGE (-875 2375);
DISPLAY INVISIBLE (-875 2375);
FORCEPROP 2 LAST SEC 1
J 0
(-875 2375);
DISPLAY 0.680851 (-875 2375);
PAINT MONO (-875 2375);
DISPLAY INVISIBLE (-875 2375);
FORCEPROP 1 LAST PATH I102
J 0
(-875 2325);
DISPLAY 0.978723 (-875 2325);
PAINT WHITE (-875 2325);
DISPLAY INVISIBLE (-875 2325);
FORCEADD RES..1
(-825 2300);
FORCEPROP 1 LAST VALUE 0.0
J 2
(-925 2300);
DISPLAY 0.617021 (-925 2300);
PAINT SKYBLUE (-925 2300);
FORCEPROP 1 LASTPIN (-925 2300) $PN 1
J 0
(-913 2312);
DISPLAY 0.617021 (-913 2312);
PAINT ORANGE (-913 2312);
FORCEPROP 1 LAST MATERIAL CHIP
J 0
(-825 2250);
DISPLAY 0.617021 (-825 2250);
PAINT SKYBLUE (-825 2250);
FORCEPROP 1 LAST LOCATION R2T60
J 0
(-875 2350);
DISPLAY 0.617021 (-875 2350);
PAINT AQUA (-875 2350);
FORCEPROP 1 LAST PART_NUMBER G21497-005
J 0
(-975 2400);
DISPLAY 0.617021 (-975 2400);
PAINT BLUE (-975 2400);
FORCEPROP 1 LASTPIN (-725 2300) $PN 2
J 0
(-763 2312);
DISPLAY 0.617021 (-763 2312);
PAINT ORANGE (-763 2312);
FORCEPROP 1 LAST WATTAGE 1/16W
J 2
(-850 2150);
DISPLAY 0.617021 (-850 2150);
PAINT SKYBLUE (-850 2150);
DISPLAY INVISIBLE (-850 2150);
FORCEPROP 1 LAST TOLERANCE 5%
J 0
(-825 2200);
DISPLAY 0.617021 (-825 2200);
PAINT SKYBLUE (-825 2200);
DISPLAY INVISIBLE (-825 2200);
FORCEPROP 2 LAST CDS_LIB mstr_discrete
J 0
(-825 2300);
PAINT ORANGE (-825 2300);
DISPLAY INVISIBLE (-825 2300);
FORCEPROP 2 LAST SEC_TYPE 0402
J 0
(-875 2500);
DISPLAY 1.021277 (-875 2500);
PAINT ORANGE (-875 2500);
DISPLAY INVISIBLE (-875 2500);
FORCEPROP 2 LAST SEC 1
J 0
(-875 2500);
DISPLAY 0.680851 (-875 2500);
PAINT MONO (-875 2500);
DISPLAY INVISIBLE (-875 2500);
FORCEPROP 1 LAST PATH I103
J 0
(-875 2450);
DISPLAY 0.978723 (-875 2450);
PAINT WHITE (-875 2450);
DISPLAY INVISIBLE (-875 2450);
FORCEPROP 1 LAST PACK_TYPE 0402
J 0
(-575 2150);
DISPLAY 0.617021 (-575 2150);
PAINT SKYBLUE (-575 2150);
DISPLAY INVISIBLE (-575 2150);
FORCEADD PVCCIO_CPU1..1
(-2200 2800);
FORCEPROP 3 LASTPIN (-2200 2750) SIG_NAME PVCCIO_CPU1\g
J 0
(-2190 2760);
DISPLAY 0.659574 (-2190 2760);
PAINT MONO (-2190 2760);
DISPLAY INVISIBLE (-2190 2760);
FORCEPROP 1 LAST BODY_TYPE PLUMBING
J 0
(-2245 2757);
DISPLAY 0.340426 (-2245 2757);
PAINT GREEN (-2245 2757);
DISPLAY INVISIBLE (-2245 2757);
FORCEPROP 1 LAST VOLTAGE 1.1V
J 0
(-2245 2757);
DISPLAY 0.340426 (-2245 2757);
PAINT SKYBLUE (-2245 2757);
DISPLAY INVISIBLE (-2245 2757);
FORCEPROP 2 LAST CDS_LIB mstr_symbols
J 0
(-2200 2800);
PAINT ORANGE (-2200 2800);
DISPLAY INVISIBLE (-2200 2800);
FORCEPROP 1 LAST PATH I105
J 0
(-2150 2825);
DISPLAY 0.872340 (-2150 2825);
PAINT AQUA (-2150 2825);
DISPLAY INVISIBLE (-2150 2825);
FORCEPROP 1 LAST HDL_POWER PVCCIO_CPU1
J 1
(-2200 2850);
DISPLAY 0.872340 (-2200 2850);
PAINT GREEN (-2200 2850);
DISPLAY INVISIBLE (-2200 2850);
FORCEADD RES..2
(-2200 2500);
FORCEPROP 1 LASTPIN (-2200 2400) $PN 2
J 0
(-2195 2410);
DISPLAY 0.617021 (-2195 2410);
PAINT ORANGE (-2195 2410);
FORCEPROP 1 LAST TOLERANCE 1%
J 0
(-2155 2525);
DISPLAY 0.617021 (-2155 2525);
PAINT SKYBLUE (-2155 2525);
FORCEPROP 1 LASTPIN (-2200 2600) $PN 1
J 0
(-2195 2562);
DISPLAY 0.617021 (-2195 2562);
PAINT ORANGE (-2195 2562);
FORCEPROP 1 LAST MATERIAL CHIP
J 0
(-2160 2425);
DISPLAY 0.617021 (-2160 2425);
PAINT SKYBLUE (-2160 2425);
FORCEPROP 1 LAST PART_NUMBER G21796-009
J 0
(-2160 2375);
DISPLAY 0.617021 (-2160 2375);
PAINT BLUE (-2160 2375);
FORCEPROP 1 LAST LOCATION R7P28
J 0
(-2155 2625);
DISPLAY 0.617021 (-2155 2625);
PAINT AQUA (-2155 2625);
FORCEPROP 1 LAST VALUE 150.0
J 0
(-2155 2575);
DISPLAY 0.617021 (-2155 2575);
PAINT SKYBLUE (-2155 2575);
FORCEPROP 1 LAST PACK_TYPE 0402
J 0
(-2160 2325);
DISPLAY 0.617021 (-2160 2325);
PAINT SKYBLUE (-2160 2325);
FORCEPROP 1 LAST WATTAGE 1/16W
J 0
(-2160 2475);
DISPLAY 0.617021 (-2160 2475);
PAINT SKYBLUE (-2160 2475);
FORCEPROP 2 LAST ROOM PROC_SIDEBAND
J 0
(-2175 2275);
PAINT ORANGE (-2175 2275);
DISPLAY INVISIBLE (-2175 2275);
FORCEPROP 2 LAST BOM_COST PROC_SIDEBAND
J 0
(-2200 2500);
PAINT MONO (-2200 2500);
DISPLAY INVISIBLE (-2200 2500);
FORCEPROP 2 LAST CDS_LIB mstr_discrete
J 0
(-2200 2500);
PAINT MONO (-2200 2500);
DISPLAY INVISIBLE (-2200 2500);
FORCEPROP 2 LAST CDS_LOCATION R7P28
J 0
(-2155 2625);
DISPLAY 0.617021 (-2155 2625);
PAINT AQUA (-2155 2625);
DISPLAY INVISIBLE (-2155 2625);
FORCEPROP 2 LAST SEC 1
J 0
(-2150 2725);
DISPLAY 0.680851 (-2150 2725);
PAINT MONO (-2150 2725);
DISPLAY INVISIBLE (-2150 2725);
FORCEPROP 2 LAST SEC_TYPE 0402
J 0
(-2150 2725);
DISPLAY 1.021277 (-2150 2725);
PAINT ORANGE (-2150 2725);
DISPLAY INVISIBLE (-2150 2725);
FORCEPROP 1 LAST PATH I106
J 0
(-2150 2675);
DISPLAY 0.978723 (-2150 2675);
PAINT WHITE (-2150 2675);
DISPLAY INVISIBLE (-2150 2675);
FORCEADD RES..2
(-1100 1900);
FORCEPROP 1 LASTPIN (-1100 1800) $PN 2
J 0
(-1095 1810);
DISPLAY 0.617021 (-1095 1810);
PAINT ORANGE (-1095 1810);
FORCEPROP 1 LASTPIN (-1100 2000) $PN 1
J 0
(-1095 1962);
DISPLAY 0.617021 (-1095 1962);
PAINT ORANGE (-1095 1962);
FORCEPROP 1 LAST PART_NUMBER G21497-005
J 0
(-1060 1775);
DISPLAY 0.617021 (-1060 1775);
PAINT BLUE (-1060 1775);
FORCEPROP 1 LAST PACK_TYPE 0402
J 0
(-1060 1725);
DISPLAY 0.617021 (-1060 1725);
PAINT SKYBLUE (-1060 1725);
FORCEPROP 1 LAST MATERIAL EMPTY
J 0
(-1060 1825);
DISPLAY 0.617021 (-1060 1825);
PAINT RED (-1060 1825);
FORCEPROP 1 LAST VALUE 0.0
J 0
(-1055 1975);
DISPLAY 0.617021 (-1055 1975);
PAINT SKYBLUE (-1055 1975);
FORCEPROP 1 LAST TOLERANCE 5%
J 0
(-1055 1925);
DISPLAY 0.617021 (-1055 1925);
PAINT SKYBLUE (-1055 1925);
FORCEPROP 1 LAST WATTAGE 1/16W
J 0
(-1060 1875);
DISPLAY 0.617021 (-1060 1875);
PAINT SKYBLUE (-1060 1875);
FORCEPROP 1 LAST LOCATION R2T59
J 0
(-1055 2025);
DISPLAY 0.617021 (-1055 2025);
PAINT AQUA (-1055 2025);
FORCEPROP 2 LAST CDS_LIB mstr_discrete
J 0
(-1100 1900);
PAINT ORANGE (-1100 1900);
DISPLAY INVISIBLE (-1100 1900);
FORCEPROP 2 LAST SEC_TYPE 0402
J 0
(-1050 2125);
DISPLAY 1.021277 (-1050 2125);
PAINT ORANGE (-1050 2125);
DISPLAY INVISIBLE (-1050 2125);
FORCEPROP 2 LAST SEC 1
J 0
(-1050 2125);
DISPLAY 0.680851 (-1050 2125);
PAINT MONO (-1050 2125);
DISPLAY INVISIBLE (-1050 2125);
FORCEPROP 1 LAST PATH I107
J 0
(-1050 2075);
DISPLAY 0.978723 (-1050 2075);
PAINT WHITE (-1050 2075);
DISPLAY INVISIBLE (-1050 2075);
FORCEADD RES..2
(-1400 1900);
FORCEPROP 1 LASTPIN (-1400 1800) $PN 2
J 0
(-1395 1810);
DISPLAY 0.617021 (-1395 1810);
PAINT ORANGE (-1395 1810);
FORCEPROP 1 LASTPIN (-1400 2000) $PN 1
J 0
(-1395 1962);
DISPLAY 0.617021 (-1395 1962);
PAINT ORANGE (-1395 1962);
FORCEPROP 1 LAST TOLERANCE 5%
J 0
(-1355 1925);
DISPLAY 0.617021 (-1355 1925);
PAINT SKYBLUE (-1355 1925);
FORCEPROP 1 LAST MATERIAL EMPTY
J 0
(-1360 1825);
DISPLAY 0.617021 (-1360 1825);
PAINT RED (-1360 1825);
FORCEPROP 1 LAST PART_NUMBER G21497-005
J 0
(-1360 1775);
DISPLAY 0.617021 (-1360 1775);
PAINT BLUE (-1360 1775);
FORCEPROP 1 LAST VALUE 0.0
J 0
(-1355 1975);
DISPLAY 0.617021 (-1355 1975);
PAINT SKYBLUE (-1355 1975);
FORCEPROP 1 LAST PACK_TYPE 0402
J 0
(-1360 1725);
DISPLAY 0.617021 (-1360 1725);
PAINT SKYBLUE (-1360 1725);
FORCEPROP 1 LAST WATTAGE 1/16W
J 0
(-1360 1875);
DISPLAY 0.617021 (-1360 1875);
PAINT SKYBLUE (-1360 1875);
FORCEPROP 1 LAST LOCATION R2T69
J 0
(-1355 2025);
DISPLAY 0.617021 (-1355 2025);
PAINT AQUA (-1355 2025);
FORCEPROP 2 LAST CDS_LIB mstr_discrete
J 0
(-1400 1900);
PAINT ORANGE (-1400 1900);
DISPLAY INVISIBLE (-1400 1900);
FORCEPROP 2 LAST SEC_TYPE 0402
J 0
(-1350 2125);
DISPLAY 1.021277 (-1350 2125);
PAINT ORANGE (-1350 2125);
DISPLAY INVISIBLE (-1350 2125);
FORCEPROP 2 LAST SEC 1
J 0
(-1350 2125);
DISPLAY 0.680851 (-1350 2125);
PAINT MONO (-1350 2125);
DISPLAY INVISIBLE (-1350 2125);
FORCEPROP 1 LAST PATH I108
J 0
(-1350 2075);
DISPLAY 0.978723 (-1350 2075);
PAINT WHITE (-1350 2075);
DISPLAY INVISIBLE (-1350 2075);
FORCEADD RES..2
(2025 2225);
FORCEPROP 1 LASTPIN (2025 2125) $PN 2
J 0
(2030 2135);
DISPLAY 0.617021 (2030 2135);
PAINT ORANGE (2030 2135);
FORCEPROP 1 LASTPIN (2025 2325) $PN 1
J 0
(2030 2287);
DISPLAY 0.617021 (2030 2287);
PAINT ORANGE (2030 2287);
FORCEPROP 1 LAST TOLERANCE 5%
J 0
(2070 2250);
DISPLAY 0.617021 (2070 2250);
PAINT SKYBLUE (2070 2250);
FORCEPROP 1 LAST MATERIAL EMPTY
J 0
(2065 2150);
DISPLAY 0.617021 (2065 2150);
PAINT RED (2065 2150);
FORCEPROP 1 LAST PACK_TYPE 0402
J 0
(2065 2050);
DISPLAY 0.617021 (2065 2050);
PAINT SKYBLUE (2065 2050);
FORCEPROP 1 LAST WATTAGE 1/16W
J 0
(2065 2200);
DISPLAY 0.617021 (2065 2200);
PAINT SKYBLUE (2065 2200);
FORCEPROP 1 LAST VALUE 0.0
J 0
(2070 2300);
DISPLAY 0.617021 (2070 2300);
PAINT SKYBLUE (2070 2300);
FORCEPROP 1 LAST LOCATION R2T71
J 0
(2070 2350);
DISPLAY 0.617021 (2070 2350);
PAINT AQUA (2070 2350);
FORCEPROP 1 LAST PART_NUMBER G21497-005
J 0
(2065 2100);
DISPLAY 0.617021 (2065 2100);
PAINT BLUE (2065 2100);
FORCEPROP 2 LAST CDS_LIB mstr_discrete
J 0
(2025 2225);
PAINT ORANGE (2025 2225);
DISPLAY INVISIBLE (2025 2225);
FORCEPROP 2 LAST SEC_TYPE 0402
J 0
(2075 2450);
DISPLAY 1.021277 (2075 2450);
PAINT ORANGE (2075 2450);
DISPLAY INVISIBLE (2075 2450);
FORCEPROP 2 LAST SEC 1
J 0
(2075 2450);
DISPLAY 0.680851 (2075 2450);
PAINT MONO (2075 2450);
DISPLAY INVISIBLE (2075 2450);
FORCEPROP 1 LAST PATH I109
J 0
(2075 2400);
DISPLAY 0.978723 (2075 2400);
PAINT WHITE (2075 2400);
DISPLAY INVISIBLE (2075 2400);
FORCEADD RES..2
(2400 2225);
FORCEPROP 1 LASTPIN (2400 2125) $PN 2
J 0
(2405 2135);
DISPLAY 0.617021 (2405 2135);
PAINT ORANGE (2405 2135);
FORCEPROP 1 LAST PACK_TYPE 0402
J 0
(2440 2050);
DISPLAY 0.617021 (2440 2050);
PAINT SKYBLUE (2440 2050);
FORCEPROP 1 LAST TOLERANCE 5%
J 0
(2445 2250);
DISPLAY 0.617021 (2445 2250);
PAINT SKYBLUE (2445 2250);
FORCEPROP 1 LAST VALUE 0.0
J 0
(2445 2300);
DISPLAY 0.617021 (2445 2300);
PAINT SKYBLUE (2445 2300);
FORCEPROP 1 LASTPIN (2400 2325) $PN 1
J 0
(2405 2287);
DISPLAY 0.617021 (2405 2287);
PAINT ORANGE (2405 2287);
FORCEPROP 1 LAST LOCATION R7D43
J 0
(2445 2350);
DISPLAY 0.617021 (2445 2350);
PAINT AQUA (2445 2350);
FORCEPROP 1 LAST WATTAGE 1/16W
J 0
(2440 2200);
DISPLAY 0.617021 (2440 2200);
PAINT SKYBLUE (2440 2200);
FORCEPROP 1 LAST MATERIAL EMPTY
J 0
(2440 2150);
DISPLAY 0.617021 (2440 2150);
PAINT RED (2440 2150);
FORCEPROP 1 LAST PART_NUMBER G21497-005
J 0
(2440 2100);
DISPLAY 0.617021 (2440 2100);
PAINT BLUE (2440 2100);
FORCEPROP 2 LAST CDS_LIB mstr_discrete
J 0
(2400 2225);
PAINT ORANGE (2400 2225);
DISPLAY INVISIBLE (2400 2225);
FORCEPROP 2 LAST SEC_TYPE 0402
J 0
(2450 2450);
DISPLAY 1.021277 (2450 2450);
PAINT ORANGE (2450 2450);
DISPLAY INVISIBLE (2450 2450);
FORCEPROP 2 LAST SEC 1
J 0
(2450 2450);
DISPLAY 0.680851 (2450 2450);
PAINT MONO (2450 2450);
DISPLAY INVISIBLE (2450 2450);
FORCEPROP 1 LAST PATH I110
J 0
(2450 2400);
DISPLAY 0.978723 (2450 2400);
PAINT WHITE (2450 2400);
DISPLAY INVISIBLE (2450 2400);
FORCEADD RES..1
(1875 3350);
FORCEPROP 1 LAST VALUE 0.0
J 2
(1775 3350);
DISPLAY 0.617021 (1775 3350);
PAINT SKYBLUE (1775 3350);
FORCEPROP 1 LAST MATERIAL CHIP
J 0
(1750 3300);
DISPLAY 0.617021 (1750 3300);
PAINT SKYBLUE (1750 3300);
FORCEPROP 1 LASTPIN (1775 3350) $PN 1
J 0
(1787 3362);
DISPLAY 0.617021 (1787 3362);
PAINT ORANGE (1787 3362);
FORCEPROP 1 LAST LOCATION R2T65
J 0
(1825 3400);
DISPLAY 0.617021 (1825 3400);
PAINT AQUA (1825 3400);
FORCEPROP 1 LASTPIN (1975 3350) $PN 2
J 0
(1937 3362);
DISPLAY 0.617021 (1937 3362);
PAINT ORANGE (1937 3362);
FORCEPROP 1 LAST PART_NUMBER G21497-005
J 0
(1850 3300);
DISPLAY 0.617021 (1850 3300);
PAINT BLUE (1850 3300);
FORCEPROP 1 LAST TOLERANCE 5%
J 0
(1875 3250);
DISPLAY 0.617021 (1875 3250);
PAINT SKYBLUE (1875 3250);
DISPLAY INVISIBLE (1875 3250);
FORCEPROP 1 LAST WATTAGE 1/16W
J 2
(1850 3200);
DISPLAY 0.617021 (1850 3200);
PAINT SKYBLUE (1850 3200);
DISPLAY INVISIBLE (1850 3200);
FORCEPROP 1 LAST PATH I111
J 0
(1825 3500);
DISPLAY 0.978723 (1825 3500);
PAINT WHITE (1825 3500);
DISPLAY INVISIBLE (1825 3500);
FORCEPROP 2 LAST SEC 1
J 0
(1825 3550);
DISPLAY 0.680851 (1825 3550);
PAINT MONO (1825 3550);
DISPLAY INVISIBLE (1825 3550);
FORCEPROP 2 LAST CDS_LIB mstr_discrete
J 0
(1875 3350);
PAINT ORANGE (1875 3350);
DISPLAY INVISIBLE (1875 3350);
FORCEPROP 2 LAST SEC_TYPE 0402
J 0
(1825 3550);
DISPLAY 1.021277 (1825 3550);
PAINT ORANGE (1825 3550);
DISPLAY INVISIBLE (1825 3550);
FORCEPROP 1 LAST PACK_TYPE 0402
J 0
(2125 3200);
DISPLAY 0.617021 (2125 3200);
PAINT SKYBLUE (2125 3200);
DISPLAY INVISIBLE (2125 3200);
FORCEADD RES..1
(1875 3100);
FORCEPROP 1 LAST MATERIAL CHIP
J 0
(1750 3050);
DISPLAY 0.617021 (1750 3050);
PAINT SKYBLUE (1750 3050);
FORCEPROP 1 LAST VALUE 0.0
J 2
(1775 3100);
DISPLAY 0.617021 (1775 3100);
PAINT SKYBLUE (1775 3100);
FORCEPROP 1 LASTPIN (1775 3100) $PN 1
J 0
(1787 3112);
DISPLAY 0.617021 (1787 3112);
PAINT ORANGE (1787 3112);
FORCEPROP 1 LAST LOCATION R2T66
J 0
(1825 3150);
DISPLAY 0.617021 (1825 3150);
PAINT AQUA (1825 3150);
FORCEPROP 1 LASTPIN (1975 3100) $PN 2
J 0
(1937 3112);
DISPLAY 0.617021 (1937 3112);
PAINT ORANGE (1937 3112);
FORCEPROP 1 LAST PART_NUMBER G21497-005
J 0
(1850 3050);
DISPLAY 0.617021 (1850 3050);
PAINT BLUE (1850 3050);
FORCEPROP 1 LAST TOLERANCE 5%
J 0
(1875 3000);
DISPLAY 0.617021 (1875 3000);
PAINT SKYBLUE (1875 3000);
DISPLAY INVISIBLE (1875 3000);
FORCEPROP 1 LAST WATTAGE 1/16W
J 2
(1850 2950);
DISPLAY 0.617021 (1850 2950);
PAINT SKYBLUE (1850 2950);
DISPLAY INVISIBLE (1850 2950);
FORCEPROP 1 LAST PATH I112
J 0
(1825 3250);
DISPLAY 0.978723 (1825 3250);
PAINT WHITE (1825 3250);
DISPLAY INVISIBLE (1825 3250);
FORCEPROP 2 LAST CDS_LIB mstr_discrete
J 0
(1875 3100);
PAINT ORANGE (1875 3100);
DISPLAY INVISIBLE (1875 3100);
FORCEPROP 2 LAST SEC_TYPE 0402
J 0
(1825 3300);
DISPLAY 1.021277 (1825 3300);
PAINT ORANGE (1825 3300);
DISPLAY INVISIBLE (1825 3300);
FORCEPROP 2 LAST SEC 1
J 0
(1825 3300);
DISPLAY 0.680851 (1825 3300);
PAINT MONO (1825 3300);
DISPLAY INVISIBLE (1825 3300);
FORCEPROP 1 LAST PACK_TYPE 0402
J 0
(2125 2950);
DISPLAY 0.617021 (2125 2950);
PAINT SKYBLUE (2125 2950);
DISPLAY INVISIBLE (2125 2950);
FORCEADD RES..1
(1875 2850);
FORCEPROP 1 LAST VALUE 0.0
J 2
(1775 2850);
DISPLAY 0.617021 (1775 2850);
PAINT SKYBLUE (1775 2850);
FORCEPROP 1 LAST MATERIAL CHIP
J 0
(1750 2800);
DISPLAY 0.617021 (1750 2800);
PAINT SKYBLUE (1750 2800);
FORCEPROP 1 LASTPIN (1775 2850) $PN 1
J 0
(1787 2862);
DISPLAY 0.617021 (1787 2862);
PAINT ORANGE (1787 2862);
FORCEPROP 1 LAST LOCATION R2T67
J 0
(1825 2900);
DISPLAY 0.617021 (1825 2900);
PAINT AQUA (1825 2900);
FORCEPROP 1 LASTPIN (1975 2850) $PN 2
J 0
(1937 2862);
DISPLAY 0.617021 (1937 2862);
PAINT ORANGE (1937 2862);
FORCEPROP 1 LAST PART_NUMBER G21497-005
J 0
(1850 2800);
DISPLAY 0.617021 (1850 2800);
PAINT BLUE (1850 2800);
FORCEPROP 1 LAST TOLERANCE 5%
J 0
(1875 2750);
DISPLAY 0.617021 (1875 2750);
PAINT SKYBLUE (1875 2750);
DISPLAY INVISIBLE (1875 2750);
FORCEPROP 1 LAST WATTAGE 1/16W
J 2
(1850 2700);
DISPLAY 0.617021 (1850 2700);
PAINT SKYBLUE (1850 2700);
DISPLAY INVISIBLE (1850 2700);
FORCEPROP 1 LAST PATH I113
J 0
(1825 3000);
DISPLAY 0.978723 (1825 3000);
PAINT WHITE (1825 3000);
DISPLAY INVISIBLE (1825 3000);
FORCEPROP 2 LAST CDS_LIB mstr_discrete
J 0
(1875 2850);
PAINT ORANGE (1875 2850);
DISPLAY INVISIBLE (1875 2850);
FORCEPROP 2 LAST SEC_TYPE 0402
J 0
(1825 3050);
DISPLAY 1.021277 (1825 3050);
PAINT ORANGE (1825 3050);
DISPLAY INVISIBLE (1825 3050);
FORCEPROP 2 LAST SEC 1
J 0
(1825 3050);
DISPLAY 0.680851 (1825 3050);
PAINT MONO (1825 3050);
DISPLAY INVISIBLE (1825 3050);
FORCEPROP 1 LAST PACK_TYPE 0402
J 0
(2125 2700);
DISPLAY 0.617021 (2125 2700);
PAINT SKYBLUE (2125 2700);
DISPLAY INVISIBLE (2125 2700);
FORCEADD RES..1
(1875 2575);
FORCEPROP 1 LAST MATERIAL CHIP
J 0
(1750 2525);
DISPLAY 0.617021 (1750 2525);
PAINT SKYBLUE (1750 2525);
FORCEPROP 1 LAST VALUE 0.0
J 2
(1775 2575);
DISPLAY 0.617021 (1775 2575);
PAINT SKYBLUE (1775 2575);
FORCEPROP 1 LASTPIN (1775 2575) $PN 1
J 0
(1787 2587);
DISPLAY 0.617021 (1787 2587);
PAINT ORANGE (1787 2587);
FORCEPROP 1 LAST LOCATION R7D41
J 0
(1825 2625);
DISPLAY 0.617021 (1825 2625);
PAINT AQUA (1825 2625);
FORCEPROP 1 LASTPIN (1975 2575) $PN 2
J 0
(1937 2587);
DISPLAY 0.617021 (1937 2587);
PAINT ORANGE (1937 2587);
FORCEPROP 1 LAST PART_NUMBER G21497-005
J 0
(1850 2525);
DISPLAY 0.617021 (1850 2525);
PAINT BLUE (1850 2525);
FORCEPROP 1 LAST TOLERANCE 5%
J 0
(1875 2475);
DISPLAY 0.617021 (1875 2475);
PAINT SKYBLUE (1875 2475);
DISPLAY INVISIBLE (1875 2475);
FORCEPROP 1 LAST WATTAGE 1/16W
J 2
(1850 2425);
DISPLAY 0.617021 (1850 2425);
PAINT SKYBLUE (1850 2425);
DISPLAY INVISIBLE (1850 2425);
FORCEPROP 1 LAST PATH I114
J 0
(1825 2725);
DISPLAY 0.978723 (1825 2725);
PAINT WHITE (1825 2725);
DISPLAY INVISIBLE (1825 2725);
FORCEPROP 2 LAST SEC 1
J 0
(1825 2775);
DISPLAY 0.680851 (1825 2775);
PAINT MONO (1825 2775);
DISPLAY INVISIBLE (1825 2775);
FORCEPROP 2 LAST CDS_LIB mstr_discrete
J 0
(1875 2575);
PAINT ORANGE (1875 2575);
DISPLAY INVISIBLE (1875 2575);
FORCEPROP 2 LAST SEC_TYPE 0402
J 0
(1825 2775);
DISPLAY 1.021277 (1825 2775);
PAINT ORANGE (1825 2775);
DISPLAY INVISIBLE (1825 2775);
FORCEPROP 1 LAST PACK_TYPE 0402
J 0
(2125 2425);
DISPLAY 0.617021 (2125 2425);
PAINT SKYBLUE (2125 2425);
DISPLAY INVISIBLE (2125 2425);
FORCEADD OFFPAGE..2
(-1325 1450);
FORCEPROP 2 LAST $XR0 145 
J 0
(-1136 1450);
DISPLAY 0.638298 (-1136 1450);
PAINT MONO (-1136 1450);
FORCEPROP 1 LAST COMMENT_BODY TRUE
J 0
(-1370 1355);
DISPLAY 0.872340 (-1370 1355);
PAINT GREEN (-1370 1355);
DISPLAY INVISIBLE (-1370 1355);
FORCEPROP 2 LAST CDS_LIB mstr_standard
J 0
(-1325 1450);
PAINT ORANGE (-1325 1450);
DISPLAY INVISIBLE (-1325 1450);
FORCEPROP 2 LAST PATH I115
J 0
(-1150 1525);
DISPLAY 1.021277 (-1150 1525);
PAINT ORANGE (-1150 1525);
DISPLAY INVISIBLE (-1150 1525);
FORCEPROP 1 LAST OFFPAGE TRUE
J 0
(-1000 1325);
DISPLAY 0.872340 (-1000 1325);
PAINT GREEN (-1000 1325);
DISPLAY INVISIBLE (-1000 1325);
FORCEADD OFFPAGE..2
(-1325 1050);
FORCEPROP 2 LAST $XR0 145 
J 0
(-1136 1050);
DISPLAY 0.638298 (-1136 1050);
PAINT MONO (-1136 1050);
FORCEPROP 1 LAST COMMENT_BODY TRUE
J 0
(-1370 955);
DISPLAY 0.872340 (-1370 955);
PAINT GREEN (-1370 955);
DISPLAY INVISIBLE (-1370 955);
FORCEPROP 2 LAST CDS_LIB mstr_standard
J 0
(-1325 1050);
PAINT ORANGE (-1325 1050);
DISPLAY INVISIBLE (-1325 1050);
FORCEPROP 2 LAST PATH I116
J 0
(-1150 1125);
DISPLAY 1.021277 (-1150 1125);
PAINT ORANGE (-1150 1125);
DISPLAY INVISIBLE (-1150 1125);
FORCEPROP 1 LAST OFFPAGE TRUE
J 0
(-1000 925);
DISPLAY 0.872340 (-1000 925);
PAINT GREEN (-1000 925);
DISPLAY INVISIBLE (-1000 925);
FORCEADD OFFPAGE..2
(-1325 675);
FORCEPROP 2 LAST $XR0 145 
J 0
(-1136 675);
DISPLAY 0.638298 (-1136 675);
PAINT MONO (-1136 675);
FORCEPROP 1 LAST COMMENT_BODY TRUE
J 0
(-1370 580);
DISPLAY 0.872340 (-1370 580);
PAINT GREEN (-1370 580);
DISPLAY INVISIBLE (-1370 580);
FORCEPROP 2 LAST CDS_LIB mstr_standard
J 0
(-1325 675);
PAINT ORANGE (-1325 675);
DISPLAY INVISIBLE (-1325 675);
FORCEPROP 2 LAST PATH I117
J 0
(-1150 750);
DISPLAY 1.021277 (-1150 750);
PAINT ORANGE (-1150 750);
DISPLAY INVISIBLE (-1150 750);
FORCEPROP 1 LAST OFFPAGE TRUE
J 0
(-1000 550);
DISPLAY 0.872340 (-1000 550);
PAINT GREEN (-1000 550);
DISPLAY INVISIBLE (-1000 550);
FORCEADD OFFPAGE..2
(-1325 275);
FORCEPROP 2 LAST $XR0 145 
J 0
(-1136 275);
DISPLAY 0.638298 (-1136 275);
PAINT MONO (-1136 275);
FORCEPROP 1 LAST COMMENT_BODY TRUE
J 0
(-1370 180);
DISPLAY 0.872340 (-1370 180);
PAINT GREEN (-1370 180);
DISPLAY INVISIBLE (-1370 180);
FORCEPROP 2 LAST CDS_LIB mstr_standard
J 0
(-1325 275);
PAINT ORANGE (-1325 275);
DISPLAY INVISIBLE (-1325 275);
FORCEPROP 2 LAST PATH I118
J 0
(-1150 350);
DISPLAY 1.021277 (-1150 350);
PAINT ORANGE (-1150 350);
DISPLAY INVISIBLE (-1150 350);
FORCEPROP 1 LAST OFFPAGE TRUE
J 0
(-1000 150);
DISPLAY 0.872340 (-1000 150);
PAINT GREEN (-1000 150);
DISPLAY INVISIBLE (-1000 150);
FORCEADD RES..1
(-2225 1450);
FORCEPROP 1 LAST VALUE 0.0
J 2
(-2325 1450);
DISPLAY 0.617021 (-2325 1450);
PAINT SKYBLUE (-2325 1450);
FORCEPROP 1 LAST WATTAGE 1/16W
J 2
(-2325 1400);
DISPLAY 0.617021 (-2325 1400);
PAINT SKYBLUE (-2325 1400);
FORCEPROP 1 LASTPIN (-2325 1450) $PN 1
J 0
(-2313 1462);
DISPLAY 0.617021 (-2313 1462);
PAINT ORANGE (-2313 1462);
FORCEPROP 1 LAST TOLERANCE 5%
J 0
(-2300 1400);
DISPLAY 0.617021 (-2300 1400);
PAINT SKYBLUE (-2300 1400);
FORCEPROP 1 LAST LOCATION R8F38
J 0
(-2275 1500);
DISPLAY 0.617021 (-2275 1500);
PAINT AQUA (-2275 1500);
FORCEPROP 1 LAST MATERIAL CHIP
J 0
(-2225 1400);
DISPLAY 0.617021 (-2225 1400);
PAINT SKYBLUE (-2225 1400);
FORCEPROP 1 LASTPIN (-2125 1450) $PN 2
J 0
(-2163 1462);
DISPLAY 0.617021 (-2163 1462);
PAINT ORANGE (-2163 1462);
FORCEPROP 1 LAST PART_NUMBER G21497-005
J 0
(-2375 1550);
DISPLAY 0.617021 (-2375 1550);
PAINT BLUE (-2375 1550);
FORCEPROP 1 LAST PACK_TYPE 0402
J 0
(-2125 1400);
DISPLAY 0.617021 (-2125 1400);
PAINT SKYBLUE (-2125 1400);
FORCEPROP 2 LAST CDS_LIB mstr_discrete
J 0
(-2225 1450);
PAINT ORANGE (-2225 1450);
DISPLAY INVISIBLE (-2225 1450);
FORCEPROP 2 LAST SEC_TYPE 0402
J 0
(-2275 1650);
DISPLAY 1.021277 (-2275 1650);
PAINT ORANGE (-2275 1650);
DISPLAY INVISIBLE (-2275 1650);
FORCEPROP 2 LAST SEC 1
J 0
(-2275 1650);
DISPLAY 0.680851 (-2275 1650);
PAINT MONO (-2275 1650);
DISPLAY INVISIBLE (-2275 1650);
FORCEPROP 1 LAST PATH I119
J 0
(-2275 1600);
DISPLAY 0.978723 (-2275 1600);
PAINT WHITE (-2275 1600);
DISPLAY INVISIBLE (-2275 1600);
FORCEADD OFFPAGE..1
(-3175 1450);
FORCEPROP 2 LAST $XR0 93 
J 0
(-3396 1450);
DISPLAY 0.638298 (-3396 1450);
PAINT MONO (-3396 1450);
FORCEPROP 2 LAST CDS_LIB mstr_standard
J 0
(-3175 1450);
PAINT ORANGE (-3175 1450);
DISPLAY INVISIBLE (-3175 1450);
FORCEPROP 2 LAST PATH I120
J 0
(-3125 1525);
DISPLAY 1.021277 (-3125 1525);
PAINT ORANGE (-3125 1525);
DISPLAY INVISIBLE (-3125 1525);
FORCEPROP 1 LAST COMMENT_BODY TRUE
J 0
(-3050 1350);
DISPLAY 0.872340 (-3050 1350);
PAINT GREEN (-3050 1350);
DISPLAY INVISIBLE (-3050 1350);
FORCEPROP 1 LAST OFFPAGE TRUE
J 0
(-2850 1325);
DISPLAY 0.872340 (-2850 1325);
PAINT GREEN (-2850 1325);
DISPLAY INVISIBLE (-2850 1325);
FORCEADD RES..1
(-2225 1050);
FORCEPROP 1 LAST TOLERANCE 5%
J 0
(-2300 1000);
DISPLAY 0.617021 (-2300 1000);
PAINT SKYBLUE (-2300 1000);
FORCEPROP 1 LAST MATERIAL CHIP
J 0
(-2225 1000);
DISPLAY 0.617021 (-2225 1000);
PAINT SKYBLUE (-2225 1000);
FORCEPROP 1 LAST WATTAGE 1/16W
J 2
(-2325 1000);
DISPLAY 0.617021 (-2325 1000);
PAINT SKYBLUE (-2325 1000);
FORCEPROP 1 LAST VALUE 0.0
J 2
(-2325 1050);
DISPLAY 0.617021 (-2325 1050);
PAINT SKYBLUE (-2325 1050);
FORCEPROP 1 LAST PART_NUMBER G21497-005
J 0
(-2375 1150);
DISPLAY 0.617021 (-2375 1150);
PAINT BLUE (-2375 1150);
FORCEPROP 1 LASTPIN (-2325 1050) $PN 1
J 0
(-2313 1062);
DISPLAY 0.617021 (-2313 1062);
PAINT ORANGE (-2313 1062);
FORCEPROP 1 LAST LOCATION R2T64
J 0
(-2275 1100);
DISPLAY 0.617021 (-2275 1100);
PAINT AQUA (-2275 1100);
FORCEPROP 1 LASTPIN (-2125 1050) $PN 2
J 0
(-2163 1062);
DISPLAY 0.617021 (-2163 1062);
PAINT ORANGE (-2163 1062);
FORCEPROP 1 LAST PACK_TYPE 0402
J 0
(-2125 1000);
DISPLAY 0.617021 (-2125 1000);
PAINT SKYBLUE (-2125 1000);
FORCEPROP 2 LAST CDS_LIB mstr_discrete
J 0
(-2225 1050);
PAINT ORANGE (-2225 1050);
DISPLAY INVISIBLE (-2225 1050);
FORCEPROP 2 LAST SEC 1
J 0
(-2275 1250);
DISPLAY 0.680851 (-2275 1250);
PAINT MONO (-2275 1250);
DISPLAY INVISIBLE (-2275 1250);
FORCEPROP 1 LAST PATH I121
J 0
(-2275 1200);
DISPLAY 0.978723 (-2275 1200);
PAINT WHITE (-2275 1200);
DISPLAY INVISIBLE (-2275 1200);
FORCEPROP 2 LAST SEC_TYPE 0402
J 0
(-2275 1250);
DISPLAY 1.021277 (-2275 1250);
PAINT ORANGE (-2275 1250);
DISPLAY INVISIBLE (-2275 1250);
FORCEADD RES..1
(-2225 675);
FORCEPROP 1 LAST WATTAGE 1/16W
J 2
(-2325 625);
DISPLAY 0.617021 (-2325 625);
PAINT SKYBLUE (-2325 625);
FORCEPROP 1 LAST VALUE 0.0
J 2
(-2325 675);
DISPLAY 0.617021 (-2325 675);
PAINT SKYBLUE (-2325 675);
FORCEPROP 1 LAST PART_NUMBER G21497-005
J 0
(-2375 775);
DISPLAY 0.617021 (-2375 775);
PAINT BLUE (-2375 775);
FORCEPROP 1 LASTPIN (-2325 675) $PN 1
J 0
(-2313 687);
DISPLAY 0.617021 (-2313 687);
PAINT ORANGE (-2313 687);
FORCEPROP 1 LAST TOLERANCE 5%
J 0
(-2300 625);
DISPLAY 0.617021 (-2300 625);
PAINT SKYBLUE (-2300 625);
FORCEPROP 1 LAST LOCATION R1T36
J 0
(-2275 725);
DISPLAY 0.617021 (-2275 725);
PAINT AQUA (-2275 725);
FORCEPROP 1 LAST MATERIAL CHIP
J 0
(-2225 625);
DISPLAY 0.617021 (-2225 625);
PAINT SKYBLUE (-2225 625);
FORCEPROP 1 LASTPIN (-2125 675) $PN 2
J 0
(-2163 687);
DISPLAY 0.617021 (-2163 687);
PAINT ORANGE (-2163 687);
FORCEPROP 1 LAST PACK_TYPE 0402
J 0
(-2125 625);
DISPLAY 0.617021 (-2125 625);
PAINT SKYBLUE (-2125 625);
FORCEPROP 2 LAST CDS_LIB mstr_discrete
J 0
(-2225 675);
PAINT ORANGE (-2225 675);
DISPLAY INVISIBLE (-2225 675);
FORCEPROP 1 LAST PATH I122
J 0
(-2275 825);
DISPLAY 0.978723 (-2275 825);
PAINT WHITE (-2275 825);
DISPLAY INVISIBLE (-2275 825);
FORCEPROP 2 LAST SEC_TYPE 0402
J 0
(-2275 875);
DISPLAY 1.021277 (-2275 875);
PAINT ORANGE (-2275 875);
DISPLAY INVISIBLE (-2275 875);
FORCEPROP 2 LAST SEC 1
J 0
(-2275 875);
DISPLAY 0.680851 (-2275 875);
PAINT MONO (-2275 875);
DISPLAY INVISIBLE (-2275 875);
FORCEADD RES..1
(-2225 275);
FORCEPROP 1 LAST WATTAGE 1/16W
J 2
(-2325 225);
DISPLAY 0.617021 (-2325 225);
PAINT SKYBLUE (-2325 225);
FORCEPROP 1 LAST VALUE 0.0
J 2
(-2325 275);
DISPLAY 0.617021 (-2325 275);
PAINT SKYBLUE (-2325 275);
FORCEPROP 1 LAST PART_NUMBER G21497-005
J 0
(-2375 375);
DISPLAY 0.617021 (-2375 375);
PAINT BLUE (-2375 375);
FORCEPROP 1 LASTPIN (-2325 275) $PN 1
J 0
(-2313 287);
DISPLAY 0.617021 (-2313 287);
PAINT ORANGE (-2313 287);
FORCEPROP 1 LAST TOLERANCE 5%
J 0
(-2300 225);
DISPLAY 0.617021 (-2300 225);
PAINT SKYBLUE (-2300 225);
FORCEPROP 1 LAST MATERIAL CHIP
J 0
(-2225 225);
DISPLAY 0.617021 (-2225 225);
PAINT SKYBLUE (-2225 225);
FORCEPROP 1 LAST LOCATION R1T37
J 0
(-2275 325);
DISPLAY 0.617021 (-2275 325);
PAINT AQUA (-2275 325);
FORCEPROP 1 LASTPIN (-2125 275) $PN 2
J 0
(-2163 287);
DISPLAY 0.617021 (-2163 287);
PAINT ORANGE (-2163 287);
FORCEPROP 1 LAST PACK_TYPE 0402
J 0
(-2125 225);
DISPLAY 0.617021 (-2125 225);
PAINT SKYBLUE (-2125 225);
FORCEPROP 2 LAST CDS_LIB mstr_discrete
J 0
(-2225 275);
PAINT ORANGE (-2225 275);
DISPLAY INVISIBLE (-2225 275);
FORCEPROP 2 LAST SEC 1
J 0
(-2275 475);
DISPLAY 0.680851 (-2275 475);
PAINT MONO (-2275 475);
DISPLAY INVISIBLE (-2275 475);
FORCEPROP 1 LAST PATH I123
J 0
(-2275 425);
DISPLAY 0.978723 (-2275 425);
PAINT WHITE (-2275 425);
DISPLAY INVISIBLE (-2275 425);
FORCEPROP 2 LAST SEC_TYPE 0402
J 0
(-2275 475);
DISPLAY 1.021277 (-2275 475);
PAINT ORANGE (-2275 475);
DISPLAY INVISIBLE (-2275 475);
FORCEADD OFFPAGE..1
(-3175 1050);
FORCEPROP 2 LAST $XR0 93 
J 0
(-3396 1050);
DISPLAY 0.638298 (-3396 1050);
PAINT MONO (-3396 1050);
FORCEPROP 2 LAST PATH I124
J 0
(-3125 1125);
DISPLAY 1.021277 (-3125 1125);
PAINT ORANGE (-3125 1125);
DISPLAY INVISIBLE (-3125 1125);
FORCEPROP 2 LAST CDS_LIB mstr_standard
J 0
(-3175 1050);
PAINT ORANGE (-3175 1050);
DISPLAY INVISIBLE (-3175 1050);
FORCEPROP 1 LAST COMMENT_BODY TRUE
J 0
(-3050 950);
DISPLAY 0.872340 (-3050 950);
PAINT GREEN (-3050 950);
DISPLAY INVISIBLE (-3050 950);
FORCEPROP 1 LAST OFFPAGE TRUE
J 0
(-2850 925);
DISPLAY 0.872340 (-2850 925);
PAINT GREEN (-2850 925);
DISPLAY INVISIBLE (-2850 925);
FORCEADD OFFPAGE..1
(-3175 675);
FORCEPROP 2 LAST $XR0 93 
J 0
(-3396 675);
DISPLAY 0.638298 (-3396 675);
PAINT MONO (-3396 675);
FORCEPROP 2 LAST CDS_LIB mstr_standard
J 0
(-3175 675);
PAINT ORANGE (-3175 675);
DISPLAY INVISIBLE (-3175 675);
FORCEPROP 2 LAST PATH I125
J 0
(-3125 750);
DISPLAY 1.021277 (-3125 750);
PAINT ORANGE (-3125 750);
DISPLAY INVISIBLE (-3125 750);
FORCEPROP 1 LAST COMMENT_BODY TRUE
J 0
(-3050 575);
DISPLAY 0.872340 (-3050 575);
PAINT GREEN (-3050 575);
DISPLAY INVISIBLE (-3050 575);
FORCEPROP 1 LAST OFFPAGE TRUE
J 0
(-2850 550);
DISPLAY 0.872340 (-2850 550);
PAINT GREEN (-2850 550);
DISPLAY INVISIBLE (-2850 550);
FORCEADD OFFPAGE..1
(-3175 275);
FORCEPROP 2 LAST $XR0 93 
J 0
(-3396 275);
DISPLAY 0.638298 (-3396 275);
PAINT MONO (-3396 275);
FORCEPROP 2 LAST PATH I126
J 0
(-3125 350);
DISPLAY 1.021277 (-3125 350);
PAINT ORANGE (-3125 350);
DISPLAY INVISIBLE (-3125 350);
FORCEPROP 2 LAST CDS_LIB mstr_standard
J 0
(-3175 275);
PAINT ORANGE (-3175 275);
DISPLAY INVISIBLE (-3175 275);
FORCEPROP 1 LAST COMMENT_BODY TRUE
J 0
(-3050 175);
DISPLAY 0.872340 (-3050 175);
PAINT GREEN (-3050 175);
DISPLAY INVISIBLE (-3050 175);
FORCEPROP 1 LAST OFFPAGE TRUE
J 0
(-2850 150);
DISPLAY 0.872340 (-2850 150);
PAINT GREEN (-2850 150);
DISPLAY INVISIBLE (-2850 150);
FORCEADD RES..2
(3700 425);
FORCEPROP 1 LASTPIN (3700 325) $PN 2
J 0
(3705 335);
DISPLAY 0.617021 (3705 335);
PAINT ORANGE (3705 335);
FORCEPROP 1 LAST TOLERANCE 1%
J 0
(3745 450);
DISPLAY 0.617021 (3745 450);
PAINT SKYBLUE (3745 450);
FORCEPROP 1 LAST PART_NUMBER G21796-026
J 0
(3740 300);
DISPLAY 0.617021 (3740 300);
PAINT BLUE (3740 300);
FORCEPROP 1 LAST PACK_TYPE 0402
J 0
(3740 250);
DISPLAY 0.617021 (3740 250);
PAINT SKYBLUE (3740 250);
FORCEPROP 1 LAST MATERIAL CHIP
J 0
(3740 350);
DISPLAY 0.617021 (3740 350);
PAINT SKYBLUE (3740 350);
FORCEPROP 1 LAST WATTAGE 1/16W
J 0
(3740 400);
DISPLAY 0.617021 (3740 400);
PAINT SKYBLUE (3740 400);
FORCEPROP 1 LAST VALUE 1.00K
J 0
(3745 500);
DISPLAY 0.617021 (3745 500);
PAINT SKYBLUE (3745 500);
FORCEPROP 1 LASTPIN (3700 525) $PN 1
J 0
(3705 487);
DISPLAY 0.617021 (3705 487);
PAINT ORANGE (3705 487);
FORCEPROP 1 LAST LOCATION R2T50
J 0
(3745 550);
DISPLAY 0.617021 (3745 550);
PAINT AQUA (3745 550);
FORCEPROP 2 LAST CDS_LIB mstr_discrete
J 0
(3700 425);
PAINT MONO (3700 425);
DISPLAY INVISIBLE (3700 425);
FORCEPROP 2 LAST BOM_COST PROC
J 0
(3700 425);
PAINT MONO (3700 425);
DISPLAY INVISIBLE (3700 425);
FORCEPROP 2 LAST SEC_TYPE 0402
J 0
(3750 650);
DISPLAY 1.021277 (3750 650);
PAINT ORANGE (3750 650);
DISPLAY INVISIBLE (3750 650);
FORCEPROP 2 LAST SEC 1
J 0
(3750 650);
DISPLAY 0.680851 (3750 650);
PAINT MONO (3750 650);
DISPLAY INVISIBLE (3750 650);
FORCEPROP 2 LAST CDS_LOCATION R2T50
J 0
(3745 550);
DISPLAY 0.617021 (3745 550);
PAINT AQUA (3745 550);
DISPLAY INVISIBLE (3745 550);
FORCEPROP 1 LAST PATH I127
J 0
(3750 600);
DISPLAY 0.978723 (3750 600);
PAINT WHITE (3750 600);
DISPLAY INVISIBLE (3750 600);
FORCEPROP 2 LAST ROOM PROC_SIDEBAND
J 0
(3650 575);
PAINT PEACH (3650 575);
DISPLAY INVISIBLE (3650 575);
FORCEADD GND..1
(3700 225);
FORCEPROP 3 LASTPIN (3700 275) SIG_NAME GND\g
J 0
(3710 285);
DISPLAY 0.659574 (3710 285);
PAINT MONO (3710 285);
DISPLAY INVISIBLE (3710 285);
FORCEPROP 1 LAST SIZE 1B
J 0
(3775 175);
DISPLAY 1.170213 (3775 175);
PAINT GREEN (3775 175);
DISPLAY INVISIBLE (3775 175);
FORCEPROP 1 LAST BODY_TYPE PLUMBING
J 0
(3655 182);
DISPLAY 0.340426 (3655 182);
PAINT GREEN (3655 182);
DISPLAY INVISIBLE (3655 182);
FORCEPROP 1 LAST VOLTAGE 0
J 0
(3700 225);
PAINT SKYBLUE (3700 225);
DISPLAY INVISIBLE (3700 225);
FORCEPROP 2 LAST CDS_LIB mstr_symbols
J 0
(3700 225);
PAINT MONO (3700 225);
DISPLAY INVISIBLE (3700 225);
FORCEPROP 1 LAST PATH I128
J 0
(3775 225);
DISPLAY 0.872340 (3775 225);
PAINT AQUA (3775 225);
DISPLAY INVISIBLE (3775 225);
FORCEPROP 1 LAST HDL_POWER GND
J 0
(3700 375);
DISPLAY 1.170213 (3700 375);
PAINT GREEN (3700 375);
DISPLAY INVISIBLE (3700 375);
FORCEADD OFFPAGE..4
(1475 3500);
FORCEPROP 2 LAST $XR0 93 
J 0
(1661 3500);
DISPLAY 0.638298 (1661 3500);
PAINT MONO (1661 3500);
FORCEPROP 1 LAST COMMENT_BODY TRUE
J 0
(1450 3400);
DISPLAY 0.872340 (1450 3400);
PAINT GREEN (1450 3400);
DISPLAY INVISIBLE (1450 3400);
FORCEPROP 2 LAST CDS_LIB mstr_standard
J 0
(1475 3500);
PAINT ORANGE (1475 3500);
DISPLAY INVISIBLE (1475 3500);
FORCEPROP 1 LAST OFFPAGE TRUE
J 0
(1800 3375);
DISPLAY 0.872340 (1800 3375);
PAINT GREEN (1800 3375);
DISPLAY INVISIBLE (1800 3375);
FORCEPROP 2 LAST PATH I129
J 0
(1650 3575);
DISPLAY 1.021277 (1650 3575);
PAINT ORANGE (1650 3575);
DISPLAY INVISIBLE (1650 3575);
FORCEADD RES..1
(-2750 3200);
FORCEPROP 1 LAST MATERIAL CHIP
J 0
(-2950 3100);
DISPLAY 0.617021 (-2950 3100);
PAINT SKYBLUE (-2950 3100);
FORCEPROP 1 LAST VALUE 0.0
J 2
(-2850 3150);
DISPLAY 0.617021 (-2850 3150);
PAINT SKYBLUE (-2850 3150);
FORCEPROP 1 LAST PACK_TYPE 0402
J 0
(-2825 3100);
DISPLAY 0.617021 (-2825 3100);
PAINT SKYBLUE (-2825 3100);
FORCEPROP 1 LASTPIN (-2850 3200) $PN 1
J 0
(-2838 3212);
DISPLAY 0.617021 (-2838 3212);
PAINT ORANGE (-2838 3212);
FORCEPROP 1 LAST TOLERANCE 5%
J 0
(-2800 3150);
DISPLAY 0.617021 (-2800 3150);
PAINT SKYBLUE (-2800 3150);
FORCEPROP 1 LASTPIN (-2650 3200) $PN 2
J 0
(-2688 3212);
DISPLAY 0.617021 (-2688 3212);
PAINT ORANGE (-2688 3212);
FORCEPROP 1 LAST WATTAGE 1/16W
J 2
(-2600 3150);
DISPLAY 0.617021 (-2600 3150);
PAINT SKYBLUE (-2600 3150);
FORCEPROP 1 LAST LOCATION R2T27
J 0
(-2800 3250);
DISPLAY 0.617021 (-2800 3250);
PAINT AQUA (-2800 3250);
FORCEPROP 1 LAST PART_NUMBER G21497-005
J 0
(-2725 3100);
DISPLAY 0.617021 (-2725 3100);
PAINT BLUE (-2725 3100);
FORCEPROP 2 LAST ROOM PROC_SIDEBAND
J 0
(-2825 3125);
DISPLAY 0.617021 (-2825 3125);
PAINT ORANGE (-2825 3125);
DISPLAY INVISIBLE (-2825 3125);
FORCEPROP 2 LAST CDS_LOCATION R2T27
J 0
(-2800 3250);
DISPLAY 0.617021 (-2800 3250);
PAINT AQUA (-2800 3250);
DISPLAY INVISIBLE (-2800 3250);
FORCEPROP 2 LAST BOM_COST PROC
J 2
(-2750 3200);
PAINT MONO (-2750 3200);
DISPLAY INVISIBLE (-2750 3200);
FORCEPROP 2 LAST CDS_LIB mstr_discrete
J 0
(-2750 3200);
PAINT ORANGE (-2750 3200);
DISPLAY INVISIBLE (-2750 3200);
FORCEPROP 2 LAST SEC_TYPE 0402
J 0
(-2800 3400);
DISPLAY 1.021277 (-2800 3400);
PAINT ORANGE (-2800 3400);
DISPLAY INVISIBLE (-2800 3400);
FORCEPROP 2 LAST SEC 1
J 0
(-2800 3400);
DISPLAY 0.680851 (-2800 3400);
PAINT MONO (-2800 3400);
DISPLAY INVISIBLE (-2800 3400);
FORCEPROP 1 LAST PATH I13
J 0
(-2800 3350);
DISPLAY 0.978723 (-2800 3350);
PAINT WHITE (-2800 3350);
DISPLAY INVISIBLE (-2800 3350);
FORCEADD OFFPAGE..5
(3225 650);
FORCEPROP 2 LAST $XR0 93 
J 0
(2971 650);
DISPLAY 0.638298 (2971 650);
PAINT MONO (2971 650);
FORCEPROP 1 LAST COMMENT_BODY TRUE
J 0
(3325 575);
DISPLAY 0.872340 (3325 575);
PAINT GREEN (3325 575);
DISPLAY INVISIBLE (3325 575);
FORCEPROP 2 LAST CDS_LIB mstr_standard
J 0
(3225 650);
PAINT ORANGE (3225 650);
DISPLAY INVISIBLE (3225 650);
FORCEPROP 2 LAST PATH I130
J 0
(3400 725);
DISPLAY 1.021277 (3400 725);
PAINT ORANGE (3400 725);
DISPLAY INVISIBLE (3400 725);
FORCEPROP 1 LAST OFFPAGE TRUE
J 0
(3550 525);
DISPLAY 0.872340 (3550 525);
PAINT GREEN (3550 525);
DISPLAY INVISIBLE (3550 525);
FORCEADD RES..1
(-2225 1250);
FORCEPROP 1 LAST WATTAGE 1/16W
J 2
(-2325 1200);
DISPLAY 0.617021 (-2325 1200);
PAINT SKYBLUE (-2325 1200);
FORCEPROP 1 LAST VALUE 0.0
J 2
(-2325 1250);
DISPLAY 0.617021 (-2325 1250);
PAINT SKYBLUE (-2325 1250);
FORCEPROP 1 LAST PART_NUMBER G21497-005
J 0
(-2375 1350);
DISPLAY 0.617021 (-2375 1350);
PAINT BLUE (-2375 1350);
FORCEPROP 1 LASTPIN (-2325 1250) $PN 1
J 0
(-2313 1262);
DISPLAY 0.617021 (-2313 1262);
PAINT ORANGE (-2313 1262);
FORCEPROP 1 LAST TOLERANCE 5%
J 0
(-2300 1200);
DISPLAY 0.617021 (-2300 1200);
PAINT SKYBLUE (-2300 1200);
FORCEPROP 1 LAST MATERIAL EMPTY
J 0
(-2225 1200);
DISPLAY 0.617021 (-2225 1200);
PAINT RED (-2225 1200);
FORCEPROP 1 LASTPIN (-2125 1250) $PN 2
J 0
(-2163 1262);
DISPLAY 0.617021 (-2163 1262);
PAINT ORANGE (-2163 1262);
FORCEPROP 1 LAST LOCATION R8F37
J 0
(-2275 1300);
DISPLAY 0.617021 (-2275 1300);
PAINT AQUA (-2275 1300);
FORCEPROP 1 LAST PACK_TYPE 0402
J 0
(-2075 1200);
DISPLAY 0.617021 (-2075 1200);
PAINT SKYBLUE (-2075 1200);
FORCEPROP 2 LAST CDS_LIB mstr_discrete
J 0
(-2225 1250);
PAINT ORANGE (-2225 1250);
DISPLAY INVISIBLE (-2225 1250);
FORCEPROP 1 LAST PATH I131
J 0
(-2275 1400);
DISPLAY 0.978723 (-2275 1400);
PAINT WHITE (-2275 1400);
DISPLAY INVISIBLE (-2275 1400);
FORCEPROP 2 LAST SEC_TYPE 0402
J 0
(-2275 1450);
DISPLAY 1.021277 (-2275 1450);
PAINT ORANGE (-2275 1450);
DISPLAY INVISIBLE (-2275 1450);
FORCEPROP 2 LAST SEC 1
J 0
(-2275 1450);
DISPLAY 0.680851 (-2275 1450);
PAINT MONO (-2275 1450);
DISPLAY INVISIBLE (-2275 1450);
FORCEADD OFFPAGE..2
(-1325 1250);
FORCEPROP 2 LAST $XR0 121 
J 0
(-1136 1250);
DISPLAY 0.638298 (-1136 1250);
PAINT MONO (-1136 1250);
FORCEPROP 1 LAST COMMENT_BODY TRUE
J 0
(-1370 1155);
DISPLAY 0.872340 (-1370 1155);
PAINT GREEN (-1370 1155);
DISPLAY INVISIBLE (-1370 1155);
FORCEPROP 2 LAST CDS_LIB mstr_standard
J 0
(-1325 1250);
PAINT ORANGE (-1325 1250);
DISPLAY INVISIBLE (-1325 1250);
FORCEPROP 2 LAST PATH I132
J 0
(-1150 1325);
DISPLAY 1.021277 (-1150 1325);
PAINT ORANGE (-1150 1325);
DISPLAY INVISIBLE (-1150 1325);
FORCEPROP 1 LAST OFFPAGE TRUE
J 0
(-1000 1125);
DISPLAY 0.872340 (-1000 1125);
PAINT GREEN (-1000 1125);
DISPLAY INVISIBLE (-1000 1125);
FORCEADD RES..1
(-2225 850);
FORCEPROP 1 LAST WATTAGE 1/16W
J 2
(-2325 800);
DISPLAY 0.617021 (-2325 800);
PAINT SKYBLUE (-2325 800);
FORCEPROP 1 LAST VALUE 0.0
J 2
(-2325 850);
DISPLAY 0.617021 (-2325 850);
PAINT SKYBLUE (-2325 850);
FORCEPROP 1 LAST PART_NUMBER G21497-005
J 0
(-2375 950);
DISPLAY 0.617021 (-2375 950);
PAINT BLUE (-2375 950);
FORCEPROP 1 LASTPIN (-2325 850) $PN 1
J 0
(-2313 862);
DISPLAY 0.617021 (-2313 862);
PAINT ORANGE (-2313 862);
FORCEPROP 1 LAST TOLERANCE 5%
J 0
(-2300 800);
DISPLAY 0.617021 (-2300 800);
PAINT SKYBLUE (-2300 800);
FORCEPROP 1 LAST MATERIAL EMPTY
J 0
(-2225 800);
DISPLAY 0.617021 (-2225 800);
PAINT RED (-2225 800);
FORCEPROP 1 LAST LOCATION R2T63
J 0
(-2275 900);
DISPLAY 0.617021 (-2275 900);
PAINT AQUA (-2275 900);
FORCEPROP 1 LASTPIN (-2125 850) $PN 2
J 0
(-2163 862);
DISPLAY 0.617021 (-2163 862);
PAINT ORANGE (-2163 862);
FORCEPROP 1 LAST PACK_TYPE 0402
J 0
(-2075 800);
DISPLAY 0.617021 (-2075 800);
PAINT SKYBLUE (-2075 800);
FORCEPROP 2 LAST CDS_LIB mstr_discrete
J 0
(-2225 850);
PAINT ORANGE (-2225 850);
DISPLAY INVISIBLE (-2225 850);
FORCEPROP 1 LAST PATH I133
J 0
(-2275 1000);
DISPLAY 0.978723 (-2275 1000);
PAINT WHITE (-2275 1000);
DISPLAY INVISIBLE (-2275 1000);
FORCEPROP 2 LAST SEC_TYPE 0402
J 0
(-2275 1050);
DISPLAY 1.021277 (-2275 1050);
PAINT ORANGE (-2275 1050);
DISPLAY INVISIBLE (-2275 1050);
FORCEPROP 2 LAST SEC 1
J 0
(-2275 1050);
DISPLAY 0.680851 (-2275 1050);
PAINT MONO (-2275 1050);
DISPLAY INVISIBLE (-2275 1050);
FORCEADD OFFPAGE..2
(-1325 850);
FORCEPROP 2 LAST $XR0 121 
J 0
(-1136 850);
DISPLAY 0.638298 (-1136 850);
PAINT MONO (-1136 850);
FORCEPROP 1 LAST COMMENT_BODY TRUE
J 0
(-1370 755);
DISPLAY 0.872340 (-1370 755);
PAINT GREEN (-1370 755);
DISPLAY INVISIBLE (-1370 755);
FORCEPROP 2 LAST CDS_LIB mstr_standard
J 0
(-1325 850);
PAINT ORANGE (-1325 850);
DISPLAY INVISIBLE (-1325 850);
FORCEPROP 2 LAST PATH I134
J 0
(-1150 925);
DISPLAY 1.021277 (-1150 925);
PAINT ORANGE (-1150 925);
DISPLAY INVISIBLE (-1150 925);
FORCEPROP 1 LAST OFFPAGE TRUE
J 0
(-1000 725);
DISPLAY 0.872340 (-1000 725);
PAINT GREEN (-1000 725);
DISPLAY INVISIBLE (-1000 725);
FORCEADD RES..1
(-2225 475);
FORCEPROP 1 LAST WATTAGE 1/16W
J 2
(-2325 425);
DISPLAY 0.617021 (-2325 425);
PAINT SKYBLUE (-2325 425);
FORCEPROP 1 LAST VALUE 0.0
J 2
(-2325 475);
DISPLAY 0.617021 (-2325 475);
PAINT SKYBLUE (-2325 475);
FORCEPROP 1 LAST TOLERANCE 5%
J 0
(-2300 425);
DISPLAY 0.617021 (-2300 425);
PAINT SKYBLUE (-2300 425);
FORCEPROP 1 LAST MATERIAL EMPTY
J 0
(-2225 425);
DISPLAY 0.617021 (-2225 425);
PAINT RED (-2225 425);
FORCEPROP 1 LASTPIN (-2125 475) $PN 2
J 0
(-2163 487);
DISPLAY 0.617021 (-2163 487);
PAINT ORANGE (-2163 487);
FORCEPROP 1 LASTPIN (-2325 475) $PN 1
J 0
(-2313 487);
DISPLAY 0.617021 (-2313 487);
PAINT ORANGE (-2313 487);
FORCEPROP 1 LAST PART_NUMBER G21497-005
J 0
(-2375 575);
DISPLAY 0.617021 (-2375 575);
PAINT BLUE (-2375 575);
FORCEPROP 1 LAST LOCATION R1T35
J 0
(-2275 525);
DISPLAY 0.617021 (-2275 525);
PAINT AQUA (-2275 525);
FORCEPROP 1 LAST PACK_TYPE 0402
J 0
(-2075 425);
DISPLAY 0.617021 (-2075 425);
PAINT SKYBLUE (-2075 425);
FORCEPROP 2 LAST CDS_LIB mstr_discrete
J 0
(-2225 475);
PAINT ORANGE (-2225 475);
DISPLAY INVISIBLE (-2225 475);
FORCEPROP 1 LAST PATH I135
J 0
(-2275 625);
DISPLAY 0.978723 (-2275 625);
PAINT WHITE (-2275 625);
DISPLAY INVISIBLE (-2275 625);
FORCEPROP 2 LAST SEC_TYPE 0402
J 0
(-2275 675);
DISPLAY 1.021277 (-2275 675);
PAINT ORANGE (-2275 675);
DISPLAY INVISIBLE (-2275 675);
FORCEPROP 2 LAST SEC 1
J 0
(-2275 675);
DISPLAY 0.680851 (-2275 675);
PAINT MONO (-2275 675);
DISPLAY INVISIBLE (-2275 675);
FORCEADD OFFPAGE..2
(-1325 475);
FORCEPROP 2 LAST $XR0 121 
J 0
(-1136 475);
DISPLAY 0.638298 (-1136 475);
PAINT MONO (-1136 475);
FORCEPROP 1 LAST COMMENT_BODY TRUE
J 0
(-1370 380);
DISPLAY 0.872340 (-1370 380);
PAINT GREEN (-1370 380);
DISPLAY INVISIBLE (-1370 380);
FORCEPROP 2 LAST CDS_LIB mstr_standard
J 0
(-1325 475);
PAINT ORANGE (-1325 475);
DISPLAY INVISIBLE (-1325 475);
FORCEPROP 2 LAST PATH I136
J 0
(-1150 550);
DISPLAY 1.021277 (-1150 550);
PAINT ORANGE (-1150 550);
DISPLAY INVISIBLE (-1150 550);
FORCEPROP 1 LAST OFFPAGE TRUE
J 0
(-1000 350);
DISPLAY 0.872340 (-1000 350);
PAINT GREEN (-1000 350);
DISPLAY INVISIBLE (-1000 350);
FORCEADD RES..1
(-2225 75);
FORCEPROP 1 LAST WATTAGE 1/16W
J 2
(-2325 25);
DISPLAY 0.617021 (-2325 25);
PAINT SKYBLUE (-2325 25);
FORCEPROP 1 LAST VALUE 0.0
J 2
(-2325 75);
DISPLAY 0.617021 (-2325 75);
PAINT SKYBLUE (-2325 75);
FORCEPROP 1 LAST PART_NUMBER G21497-005
J 0
(-2375 175);
DISPLAY 0.617021 (-2375 175);
PAINT BLUE (-2375 175);
FORCEPROP 1 LASTPIN (-2325 75) $PN 1
J 0
(-2313 87);
DISPLAY 0.617021 (-2313 87);
PAINT ORANGE (-2313 87);
FORCEPROP 1 LAST TOLERANCE 5%
J 0
(-2300 25);
DISPLAY 0.617021 (-2300 25);
PAINT SKYBLUE (-2300 25);
FORCEPROP 1 LAST MATERIAL EMPTY
J 0
(-2225 25);
DISPLAY 0.617021 (-2225 25);
PAINT RED (-2225 25);
FORCEPROP 1 LAST LOCATION R1T38
J 0
(-2275 125);
DISPLAY 0.617021 (-2275 125);
PAINT AQUA (-2275 125);
FORCEPROP 1 LASTPIN (-2125 75) $PN 2
J 0
(-2163 87);
DISPLAY 0.617021 (-2163 87);
PAINT ORANGE (-2163 87);
FORCEPROP 1 LAST PACK_TYPE 0402
J 0
(-2125 25);
DISPLAY 0.617021 (-2125 25);
PAINT SKYBLUE (-2125 25);
FORCEPROP 2 LAST CDS_LIB mstr_discrete
J 0
(-2225 75);
PAINT ORANGE (-2225 75);
DISPLAY INVISIBLE (-2225 75);
FORCEPROP 1 LAST PATH I137
J 0
(-2275 225);
DISPLAY 0.978723 (-2275 225);
PAINT WHITE (-2275 225);
DISPLAY INVISIBLE (-2275 225);
FORCEPROP 2 LAST SEC_TYPE 0402
J 0
(-2275 275);
DISPLAY 1.021277 (-2275 275);
PAINT ORANGE (-2275 275);
DISPLAY INVISIBLE (-2275 275);
FORCEPROP 2 LAST SEC 1
J 0
(-2275 275);
DISPLAY 0.680851 (-2275 275);
PAINT MONO (-2275 275);
DISPLAY INVISIBLE (-2275 275);
FORCEADD OFFPAGE..2
(-1325 75);
FORCEPROP 2 LAST $XR0 121 
J 0
(-1136 75);
DISPLAY 0.638298 (-1136 75);
PAINT MONO (-1136 75);
FORCEPROP 1 LAST OFFPAGE TRUE
J 0
(-1000 -50);
DISPLAY 0.872340 (-1000 -50);
PAINT GREEN (-1000 -50);
DISPLAY INVISIBLE (-1000 -50);
FORCEPROP 1 LAST COMMENT_BODY TRUE
J 0
(-1370 -20);
DISPLAY 0.872340 (-1370 -20);
PAINT GREEN (-1370 -20);
DISPLAY INVISIBLE (-1370 -20);
FORCEPROP 2 LAST CDS_LIB mstr_standard
J 0
(-1325 75);
PAINT ORANGE (-1325 75);
DISPLAY INVISIBLE (-1325 75);
FORCEPROP 2 LAST PATH I138
J 0
(-1150 150);
DISPLAY 1.021277 (-1150 150);
PAINT ORANGE (-1150 150);
DISPLAY INVISIBLE (-1150 150);
FORCEADD RES..2
(-2475 2525);
FORCEPROP 1 LASTPIN (-2475 2425) $PN 2
J 0
(-2470 2435);
DISPLAY 0.617021 (-2470 2435);
PAINT ORANGE (-2470 2435);
FORCEPROP 1 LAST PACK_TYPE 0402
J 0
(-2435 2350);
DISPLAY 0.617021 (-2435 2350);
PAINT SKYBLUE (-2435 2350);
FORCEPROP 1 LAST MATERIAL CHIP
J 0
(-2435 2450);
DISPLAY 0.617021 (-2435 2450);
PAINT SKYBLUE (-2435 2450);
FORCEPROP 1 LAST WATTAGE 1/16W
J 0
(-2435 2500);
DISPLAY 0.617021 (-2435 2500);
PAINT SKYBLUE (-2435 2500);
FORCEPROP 1 LAST PART_NUMBER G21796-009
J 0
(-2435 2400);
DISPLAY 0.617021 (-2435 2400);
PAINT BLUE (-2435 2400);
FORCEPROP 1 LAST TOLERANCE 1%
J 0
(-2430 2550);
DISPLAY 0.617021 (-2430 2550);
PAINT SKYBLUE (-2430 2550);
FORCEPROP 1 LASTPIN (-2475 2625) $PN 1
J 0
(-2470 2587);
DISPLAY 0.617021 (-2470 2587);
PAINT ORANGE (-2470 2587);
FORCEPROP 1 LAST VALUE 150.0
J 0
(-2430 2600);
DISPLAY 0.617021 (-2430 2600);
PAINT SKYBLUE (-2430 2600);
FORCEPROP 1 LAST LOCATION R2T72
J 0
(-2430 2650);
DISPLAY 0.617021 (-2430 2650);
PAINT AQUA (-2430 2650);
FORCEPROP 2 LAST ROOM PROC_SIDEBAND
J 0
(-2450 2300);
PAINT ORANGE (-2450 2300);
DISPLAY INVISIBLE (-2450 2300);
FORCEPROP 2 LAST BOM_COST PROC_SIDEBAND
J 0
(-2475 2525);
PAINT MONO (-2475 2525);
DISPLAY INVISIBLE (-2475 2525);
FORCEPROP 2 LAST CDS_LIB mstr_discrete
J 0
(-2475 2525);
PAINT MONO (-2475 2525);
DISPLAY INVISIBLE (-2475 2525);
FORCEPROP 2 LAST SEC 1
J 0
(-2425 2750);
DISPLAY 0.680851 (-2425 2750);
PAINT MONO (-2425 2750);
DISPLAY INVISIBLE (-2425 2750);
FORCEPROP 2 LAST SEC_TYPE 0402
J 0
(-2425 2750);
DISPLAY 1.021277 (-2425 2750);
PAINT ORANGE (-2425 2750);
DISPLAY INVISIBLE (-2425 2750);
FORCEPROP 0 LAST CDS_SEC 1
J 0
(-2425 2700);
PAINT ORANGE (-2425 2700);
DISPLAY INVISIBLE (-2425 2700);
FORCEPROP 1 LAST PATH I143
J 0
(-2425 2700);
DISPLAY 0.978723 (-2425 2700);
PAINT WHITE (-2425 2700);
DISPLAY INVISIBLE (-2425 2700);
FORCEPROP 2 LAST CDS_LOCATION R2T72
J 0
(-2430 2650);
DISPLAY 0.617021 (-2430 2650);
PAINT AQUA (-2430 2650);
DISPLAY INVISIBLE (-2430 2650);
FORCEADD RES..2
(-1900 2500);
FORCEPROP 1 LAST TOLERANCE 1%
J 0
(-1855 2525);
DISPLAY 0.617021 (-1855 2525);
PAINT SKYBLUE (-1855 2525);
FORCEPROP 1 LAST WATTAGE 1/16W
J 0
(-1860 2475);
DISPLAY 0.617021 (-1860 2475);
PAINT SKYBLUE (-1860 2475);
FORCEPROP 1 LAST PACK_TYPE 0402
J 0
(-1860 2325);
DISPLAY 0.617021 (-1860 2325);
PAINT SKYBLUE (-1860 2325);
FORCEPROP 1 LAST MATERIAL CHIP
J 0
(-1860 2425);
DISPLAY 0.617021 (-1860 2425);
PAINT SKYBLUE (-1860 2425);
FORCEPROP 1 LAST PART_NUMBER G21796-009
J 0
(-1860 2375);
DISPLAY 0.617021 (-1860 2375);
PAINT BLUE (-1860 2375);
FORCEPROP 1 LASTPIN (-1900 2600) $PN 1
J 0
(-1895 2562);
DISPLAY 0.617021 (-1895 2562);
PAINT ORANGE (-1895 2562);
FORCEPROP 1 LAST LOCATION R2T73
J 0
(-1855 2625);
DISPLAY 0.617021 (-1855 2625);
PAINT AQUA (-1855 2625);
FORCEPROP 1 LAST VALUE 150.0
J 0
(-1855 2575);
DISPLAY 0.617021 (-1855 2575);
PAINT SKYBLUE (-1855 2575);
FORCEPROP 1 LASTPIN (-1900 2400) $PN 2
J 0
(-1895 2410);
DISPLAY 0.617021 (-1895 2410);
PAINT ORANGE (-1895 2410);
FORCEPROP 2 LAST ROOM PROC_SIDEBAND
J 0
(-1875 2275);
PAINT ORANGE (-1875 2275);
DISPLAY INVISIBLE (-1875 2275);
FORCEPROP 2 LAST CDS_LIB mstr_discrete
J 0
(-1900 2500);
PAINT MONO (-1900 2500);
DISPLAY INVISIBLE (-1900 2500);
FORCEPROP 2 LAST BOM_COST PROC_SIDEBAND
J 0
(-1900 2500);
PAINT MONO (-1900 2500);
DISPLAY INVISIBLE (-1900 2500);
FORCEPROP 2 LAST SEC_TYPE 0402
J 0
(-1850 2725);
DISPLAY 1.021277 (-1850 2725);
PAINT ORANGE (-1850 2725);
DISPLAY INVISIBLE (-1850 2725);
FORCEPROP 1 LAST PATH I144
J 0
(-1850 2675);
DISPLAY 0.978723 (-1850 2675);
PAINT WHITE (-1850 2675);
DISPLAY INVISIBLE (-1850 2675);
FORCEPROP 2 LAST SEC 1
J 0
(-1850 2725);
DISPLAY 0.680851 (-1850 2725);
PAINT MONO (-1850 2725);
DISPLAY INVISIBLE (-1850 2725);
FORCEPROP 0 LAST CDS_SEC 1
J 0
(-1850 2675);
PAINT ORANGE (-1850 2675);
DISPLAY INVISIBLE (-1850 2675);
FORCEPROP 2 LAST CDS_LOCATION R2T73
J 0
(-1855 2625);
DISPLAY 0.617021 (-1855 2625);
PAINT AQUA (-1855 2625);
DISPLAY INVISIBLE (-1855 2625);
FORCEADD RES..1
(-2750 3425);
FORCEPROP 1 LAST VALUE 0.0
J 2
(-2850 3375);
DISPLAY 0.617021 (-2850 3375);
PAINT SKYBLUE (-2850 3375);
FORCEPROP 1 LAST MATERIAL CHIP
J 0
(-2950 3325);
DISPLAY 0.617021 (-2950 3325);
PAINT SKYBLUE (-2950 3325);
FORCEPROP 1 LAST PACK_TYPE 0402
J 0
(-2825 3325);
DISPLAY 0.617021 (-2825 3325);
PAINT SKYBLUE (-2825 3325);
FORCEPROP 1 LASTPIN (-2850 3425) $PN 1
J 0
(-2838 3437);
DISPLAY 0.617021 (-2838 3437);
PAINT ORANGE (-2838 3437);
FORCEPROP 1 LAST TOLERANCE 5%
J 0
(-2800 3375);
DISPLAY 0.617021 (-2800 3375);
PAINT SKYBLUE (-2800 3375);
FORCEPROP 1 LASTPIN (-2650 3425) $PN 2
J 0
(-2688 3437);
DISPLAY 0.617021 (-2688 3437);
PAINT ORANGE (-2688 3437);
FORCEPROP 1 LAST WATTAGE 1/16W
J 2
(-2600 3375);
DISPLAY 0.617021 (-2600 3375);
PAINT SKYBLUE (-2600 3375);
FORCEPROP 1 LAST LOCATION R2T32
J 0
(-2800 3475);
DISPLAY 0.617021 (-2800 3475);
PAINT AQUA (-2800 3475);
FORCEPROP 1 LAST PART_NUMBER G21497-005
J 0
(-2725 3325);
DISPLAY 0.617021 (-2725 3325);
PAINT BLUE (-2725 3325);
FORCEPROP 2 LAST ROOM PROC_SIDEBAND
J 0
(-2825 3350);
DISPLAY 0.617021 (-2825 3350);
PAINT ORANGE (-2825 3350);
DISPLAY INVISIBLE (-2825 3350);
FORCEPROP 2 LAST CDS_LOCATION R2T32
J 0
(-2800 3475);
DISPLAY 0.617021 (-2800 3475);
PAINT AQUA (-2800 3475);
DISPLAY INVISIBLE (-2800 3475);
FORCEPROP 2 LAST BOM_COST PROC
J 2
(-2750 3425);
PAINT MONO (-2750 3425);
DISPLAY INVISIBLE (-2750 3425);
FORCEPROP 2 LAST CDS_LIB mstr_discrete
J 0
(-2750 3425);
PAINT ORANGE (-2750 3425);
DISPLAY INVISIBLE (-2750 3425);
FORCEPROP 1 LAST PATH I15
J 0
(-2800 3575);
DISPLAY 0.978723 (-2800 3575);
PAINT WHITE (-2800 3575);
DISPLAY INVISIBLE (-2800 3575);
FORCEPROP 2 LAST SEC 1
J 0
(-2800 3625);
DISPLAY 0.680851 (-2800 3625);
PAINT MONO (-2800 3625);
DISPLAY INVISIBLE (-2800 3625);
FORCEPROP 2 LAST SEC_TYPE 0402
J 0
(-2800 3625);
DISPLAY 1.021277 (-2800 3625);
PAINT ORANGE (-2800 3625);
DISPLAY INVISIBLE (-2800 3625);
FORCEADD RES..1
(-2750 3725);
FORCEPROP 1 LAST VALUE 0.0
J 2
(-2850 3675);
DISPLAY 0.617021 (-2850 3675);
PAINT SKYBLUE (-2850 3675);
FORCEPROP 1 LAST MATERIAL CHIP
J 0
(-2950 3625);
DISPLAY 0.617021 (-2950 3625);
PAINT SKYBLUE (-2950 3625);
FORCEPROP 1 LAST LOCATION R2T20
J 0
(-2825 3800);
DISPLAY 0.617021 (-2825 3800);
PAINT AQUA (-2825 3800);
FORCEPROP 1 LAST PACK_TYPE 0402
J 0
(-2825 3625);
DISPLAY 0.617021 (-2825 3625);
PAINT SKYBLUE (-2825 3625);
FORCEPROP 1 LASTPIN (-2850 3725) $PN 1
J 0
(-2838 3737);
DISPLAY 0.617021 (-2838 3737);
PAINT MONO (-2838 3737);
FORCEPROP 1 LAST TOLERANCE 5%
J 0
(-2800 3675);
DISPLAY 0.617021 (-2800 3675);
PAINT SKYBLUE (-2800 3675);
FORCEPROP 1 LASTPIN (-2650 3725) $PN 2
J 0
(-2688 3737);
DISPLAY 0.617021 (-2688 3737);
PAINT MONO (-2688 3737);
FORCEPROP 1 LAST WATTAGE 1/16W
J 2
(-2600 3675);
DISPLAY 0.617021 (-2600 3675);
PAINT SKYBLUE (-2600 3675);
FORCEPROP 1 LAST PART_NUMBER G21497-005
J 0
(-2725 3625);
DISPLAY 0.617021 (-2725 3625);
PAINT BLUE (-2725 3625);
FORCEPROP 2 LAST CDS_LOCATION R2T20
J 0
(-2825 3800);
DISPLAY 0.617021 (-2825 3800);
PAINT AQUA (-2825 3800);
DISPLAY INVISIBLE (-2825 3800);
FORCEPROP 2 LAST ROOM PROC_SIDEBAND
J 0
(-2825 3650);
DISPLAY 0.617021 (-2825 3650);
PAINT ORANGE (-2825 3650);
DISPLAY INVISIBLE (-2825 3650);
FORCEPROP 2 LAST CDS_LIB mstr_discrete
J 0
(-2750 3725);
PAINT ORANGE (-2750 3725);
DISPLAY INVISIBLE (-2750 3725);
FORCEPROP 2 LAST BOM_COST PROC
J 0
(-2750 3725);
PAINT MONO (-2750 3725);
DISPLAY INVISIBLE (-2750 3725);
FORCEPROP 2 LAST SEC 1
J 0
(-2800 3925);
DISPLAY 0.680851 (-2800 3925);
PAINT MONO (-2800 3925);
DISPLAY INVISIBLE (-2800 3925);
FORCEPROP 2 LAST SEC_TYPE 0402
J 0
(-2800 3925);
DISPLAY 1.021277 (-2800 3925);
PAINT ORANGE (-2800 3925);
DISPLAY INVISIBLE (-2800 3925);
FORCEPROP 1 LAST PATH I16
J 0
(-2800 3875);
DISPLAY 0.978723 (-2800 3875);
PAINT WHITE (-2800 3875);
DISPLAY INVISIBLE (-2800 3875);
FORCEADD OFFPAGE..1
(-3400 3975);
FORCEPROP 2 LAST $XR0 21 
J 0
(-3621 3975);
DISPLAY 0.638298 (-3621 3975);
PAINT MONO (-3621 3975);
FORCEPROP 2 LAST PATH I19
J 0
(-3600 4025);
DISPLAY 1.021277 (-3600 4025);
PAINT ORANGE (-3600 4025);
DISPLAY INVISIBLE (-3600 4025);
FORCEPROP 2 LAST CDS_LIB mstr_standard
J 0
(-3400 3975);
PAINT ORANGE (-3400 3975);
DISPLAY INVISIBLE (-3400 3975);
FORCEPROP 1 LAST COMMENT_BODY TRUE
J 0
(-3275 3875);
DISPLAY 1.170213 (-3275 3875);
PAINT GREEN (-3275 3875);
DISPLAY INVISIBLE (-3275 3875);
FORCEPROP 1 LAST OFFPAGE TRUE
J 0
(-3075 3850);
PAINT GREEN (-3075 3850);
DISPLAY INVISIBLE (-3075 3850);
FORCEADD RES..1
(-2750 3975);
FORCEPROP 1 LAST VALUE 0.0
J 2
(-2850 3925);
DISPLAY 0.617021 (-2850 3925);
PAINT SKYBLUE (-2850 3925);
FORCEPROP 1 LAST MATERIAL CHIP
J 0
(-2950 3875);
DISPLAY 0.617021 (-2950 3875);
PAINT SKYBLUE (-2950 3875);
FORCEPROP 1 LAST LOCATION R2T17
J 0
(-2825 4050);
DISPLAY 0.617021 (-2825 4050);
PAINT AQUA (-2825 4050);
FORCEPROP 1 LAST PACK_TYPE 0402
J 0
(-2825 3875);
DISPLAY 0.617021 (-2825 3875);
PAINT SKYBLUE (-2825 3875);
FORCEPROP 1 LASTPIN (-2850 3975) $PN 1
J 0
(-2838 3987);
DISPLAY 0.617021 (-2838 3987);
PAINT MONO (-2838 3987);
FORCEPROP 1 LAST TOLERANCE 5%
J 0
(-2800 3925);
DISPLAY 0.617021 (-2800 3925);
PAINT SKYBLUE (-2800 3925);
FORCEPROP 1 LASTPIN (-2650 3975) $PN 2
J 0
(-2688 3987);
DISPLAY 0.617021 (-2688 3987);
PAINT MONO (-2688 3987);
FORCEPROP 1 LAST WATTAGE 1/16W
J 2
(-2600 3925);
DISPLAY 0.617021 (-2600 3925);
PAINT SKYBLUE (-2600 3925);
FORCEPROP 1 LAST PART_NUMBER G21497-005
J 0
(-2725 3875);
DISPLAY 0.617021 (-2725 3875);
PAINT BLUE (-2725 3875);
FORCEPROP 2 LAST CDS_LOCATION R2T17
J 0
(-2825 4050);
DISPLAY 0.617021 (-2825 4050);
PAINT AQUA (-2825 4050);
DISPLAY INVISIBLE (-2825 4050);
FORCEPROP 2 LAST ROOM PROC_SIDEBAND
J 0
(-2825 3900);
DISPLAY 0.617021 (-2825 3900);
PAINT ORANGE (-2825 3900);
DISPLAY INVISIBLE (-2825 3900);
FORCEPROP 2 LAST BOM_COST PROC
J 2
(-2750 3975);
PAINT MONO (-2750 3975);
DISPLAY INVISIBLE (-2750 3975);
FORCEPROP 2 LAST CDS_LIB mstr_discrete
J 0
(-2750 3975);
PAINT ORANGE (-2750 3975);
DISPLAY INVISIBLE (-2750 3975);
FORCEPROP 1 LAST PATH I23
J 0
(-2800 4125);
DISPLAY 0.978723 (-2800 4125);
PAINT WHITE (-2800 4125);
DISPLAY INVISIBLE (-2800 4125);
FORCEPROP 2 LAST SEC 1
J 0
(-2800 4175);
DISPLAY 0.680851 (-2800 4175);
PAINT MONO (-2800 4175);
DISPLAY INVISIBLE (-2800 4175);
FORCEPROP 2 LAST SEC_TYPE 0402
J 0
(-2800 4175);
DISPLAY 1.021277 (-2800 4175);
PAINT ORANGE (-2800 4175);
DISPLAY INVISIBLE (-2800 4175);
FORCEADD GND..1
(-200 2825);
FORCEPROP 3 LASTPIN (-200 2875) SIG_NAME GND\g
J 0
(-190 2885);
DISPLAY 0.659574 (-190 2885);
PAINT MONO (-190 2885);
DISPLAY INVISIBLE (-190 2885);
FORCEPROP 1 LAST BODY_TYPE PLUMBING
J 0
(-245 2782);
DISPLAY 0.340426 (-245 2782);
PAINT GREEN (-245 2782);
DISPLAY INVISIBLE (-245 2782);
FORCEPROP 1 LAST SIZE 1B
J 0
(-125 2775);
DISPLAY 1.212766 (-125 2775);
PAINT GREEN (-125 2775);
DISPLAY INVISIBLE (-125 2775);
FORCEPROP 2 LAST CDS_LIB mstr_symbols
J 0
(-200 2825);
PAINT MONO (-200 2825);
DISPLAY INVISIBLE (-200 2825);
FORCEPROP 1 LAST VOLTAGE 0
J 0
(-200 2825);
PAINT SKYBLUE (-200 2825);
DISPLAY INVISIBLE (-200 2825);
FORCEPROP 1 LAST HDL_POWER GND
J 0
(-200 2975);
DISPLAY 1.212766 (-200 2975);
PAINT GREEN (-200 2975);
DISPLAY INVISIBLE (-200 2975);
FORCEPROP 1 LAST PATH I29
J 0
(-125 2825);
DISPLAY 0.872340 (-125 2825);
PAINT AQUA (-125 2825);
DISPLAY INVISIBLE (-125 2825);
FORCEADD GTL2014..1
R 2
(425 3350);
FORCEPROP 2 LASTPIN (-25 2950) $PN 7
J 2
(-35 2960);
DISPLAY 0.617021 (-35 2960);
PAINT ORANGE (-35 2960);
FORCEPROP 2 LASTPIN (-25 3000) $PN 8
J 2
(-35 3010);
DISPLAY 0.617021 (-35 3010);
PAINT ORANGE (-35 3010);
FORCEPROP 2 LASTPIN (-25 3050) $PN 11
J 2
(-35 3060);
DISPLAY 0.617021 (-35 3060);
PAINT ORANGE (-35 3060);
FORCEPROP 2 LASTPIN (-25 3350) $PN 6
J 2
(-35 3360);
DISPLAY 0.617021 (-35 3360);
PAINT ORANGE (-35 3360);
FORCEPROP 2 LASTPIN (-25 3300) $PN 5
J 2
(-35 3310);
DISPLAY 0.617021 (-35 3310);
PAINT ORANGE (-35 3310);
FORCEPROP 2 LASTPIN (-25 3250) $PN 3
J 2
(-35 3260);
DISPLAY 0.617021 (-35 3260);
PAINT ORANGE (-35 3260);
FORCEPROP 2 LASTPIN (-25 3200) $PN 2
J 2
(-35 3210);
DISPLAY 0.617021 (-35 3210);
PAINT ORANGE (-35 3210);
FORCEPROP 1 LAST PART_NUMBER D66151-001
J 2
(825 2825);
DISPLAY 0.617021 (825 2825);
PAINT BLUE (825 2825);
FORCEPROP 2 LASTPIN (875 3200) $PN 13
J 0
(885 3210);
DISPLAY 0.617021 (885 3210);
PAINT ORANGE (885 3210);
FORCEPROP 2 LASTPIN (875 3250) $PN 12
J 0
(885 3260);
DISPLAY 0.617021 (885 3260);
PAINT ORANGE (885 3260);
FORCEPROP 2 LASTPIN (875 3300) $PN 10
J 0
(885 3310);
DISPLAY 0.617021 (885 3310);
PAINT ORANGE (885 3310);
FORCEPROP 2 LASTPIN (875 3350) $PN 9
J 0
(885 3360);
DISPLAY 0.617021 (885 3360);
PAINT ORANGE (885 3360);
FORCEPROP 2 LASTPIN (875 3500) $PN 1
J 0
(885 3510);
DISPLAY 0.617021 (885 3510);
PAINT ORANGE (885 3510);
FORCEPROP 1 LAST MATERIAL IC
J 2
(825 3850);
DISPLAY 0.617021 (825 3850);
PAINT SKYBLUE (825 3850);
FORCEPROP 1 LAST LOCATION U2T4
J 2
(825 3900);
DISPLAY 0.617021 (825 3900);
PAINT AQUA (825 3900);
FORCEPROP 2 LASTPIN (875 3600) $PN 4
J 0
(885 3610);
DISPLAY 0.617021 (885 3610);
PAINT ORANGE (885 3610);
FORCEPROP 2 LASTPIN (875 3650) $PN 14
J 0
(885 3660);
DISPLAY 0.617021 (885 3660);
PAINT ORANGE (885 3660);
FORCEPROP 2 LAST BOM_COST PROC
J 2
(425 3350);
PAINT MONO (425 3350);
DISPLAY INVISIBLE (425 3350);
FORCEPROP 2 LAST CDS_LIB mstr_digital
J 2
(425 3350);
PAINT MONO (425 3350);
DISPLAY INVISIBLE (425 3350);
FORCEPROP 1 LAST PATH I30
J 2
(425 3850);
PAINT GREEN (425 3850);
DISPLAY INVISIBLE (425 3850);
FORCEPROP 2 LAST SEC_TYPE SM
J 0
(825 3950);
DISPLAY 1.021277 (825 3950);
PAINT ORANGE (825 3950);
DISPLAY INVISIBLE (825 3950);
FORCEPROP 2 LAST SEC 1
J 0
(825 3950);
DISPLAY 0.680851 (825 3950);
PAINT MONO (825 3950);
DISPLAY INVISIBLE (825 3950);
FORCEPROP 2 LAST CDS_LOCATION U2T4
J 2
(825 3900);
DISPLAY 0.617021 (825 3900);
PAINT AQUA (825 3900);
DISPLAY INVISIBLE (825 3900);
FORCEPROP 2 LAST ROOM PROC_SIDEBAND
J 2
(825 4000);
PAINT MONO (825 4000);
DISPLAY INVISIBLE (825 4000);
FORCEPROP 1 LAST PACK_TYPE SM
J 2
(825 3950);
PAINT SKYBLUE (825 3950);
DISPLAY INVISIBLE (825 3950);
FORCEADD RES..1
(2950 2850);
FORCEPROP 1 LAST VALUE 33.2
J 2
(2900 2800);
DISPLAY 0.617021 (2900 2800);
PAINT SKYBLUE (2900 2800);
FORCEPROP 1 LAST WATTAGE 1/16W
J 2
(2825 2750);
DISPLAY 0.617021 (2825 2750);
PAINT SKYBLUE (2825 2750);
FORCEPROP 1 LAST MATERIAL CHIP
J 0
(2850 2750);
DISPLAY 0.617021 (2850 2750);
PAINT SKYBLUE (2850 2750);
FORCEPROP 1 LAST TOLERANCE 1%
J 0
(2925 2800);
DISPLAY 0.617021 (2925 2800);
PAINT SKYBLUE (2925 2800);
FORCEPROP 1 LASTPIN (2850 2850) $PN 1
J 0
(2862 2862);
DISPLAY 0.617021 (2862 2862);
PAINT ORANGE (2862 2862);
FORCEPROP 1 LAST LOCATION R2T38
J 0
(2900 2900);
DISPLAY 0.617021 (2900 2900);
PAINT AQUA (2900 2900);
FORCEPROP 1 LASTPIN (3050 2850) $PN 2
J 0
(3012 2862);
DISPLAY 0.617021 (3012 2862);
PAINT ORANGE (3012 2862);
FORCEPROP 1 LAST PART_NUMBER G21796-074
J 0
(2950 2750);
DISPLAY 0.617021 (2950 2750);
PAINT BLUE (2950 2750);
FORCEPROP 1 LAST PACK_TYPE 0402
J 0
(3000 2800);
DISPLAY 0.617021 (3000 2800);
PAINT SKYBLUE (3000 2800);
FORCEPROP 2 LAST ROOM PROC_SIDEBAND
J 0
(2875 2775);
DISPLAY 0.617021 (2875 2775);
PAINT ORANGE (2875 2775);
DISPLAY INVISIBLE (2875 2775);
FORCEPROP 2 LAST CDS_LOCATION R2T38
J 0
(2900 2900);
DISPLAY 0.617021 (2900 2900);
PAINT AQUA (2900 2900);
DISPLAY INVISIBLE (2900 2900);
FORCEPROP 1 LAST PATH I39
J 0
(2900 3000);
DISPLAY 0.978723 (2900 3000);
PAINT WHITE (2900 3000);
DISPLAY INVISIBLE (2900 3000);
FORCEPROP 2 LAST BOM_COST PROC
J 2
(2950 2850);
PAINT MONO (2950 2850);
DISPLAY INVISIBLE (2950 2850);
FORCEPROP 2 LAST CDS_LIB mstr_discrete
J 0
(2950 2850);
PAINT ORANGE (2950 2850);
DISPLAY INVISIBLE (2950 2850);
FORCEPROP 2 LAST SEC_TYPE 0402
J 0
(2900 3050);
DISPLAY 1.021277 (2900 3050);
PAINT ORANGE (2900 3050);
DISPLAY INVISIBLE (2900 3050);
FORCEPROP 2 LAST SEC 1
J 0
(2900 3050);
DISPLAY 0.680851 (2900 3050);
PAINT MONO (2900 3050);
DISPLAY INVISIBLE (2900 3050);
FORCEADD OFFPAGE..1
(-3400 3200);
FORCEPROP 2 LAST $XR0 55 
J 0
(-3621 3200);
DISPLAY 0.638298 (-3621 3200);
PAINT MONO (-3621 3200);
FORCEPROP 2 LAST PATH I4
J 0
(-3650 3250);
DISPLAY 1.021277 (-3650 3250);
PAINT ORANGE (-3650 3250);
DISPLAY INVISIBLE (-3650 3250);
FORCEPROP 2 LAST CDS_LIB mstr_standard
J 0
(-3400 3200);
PAINT ORANGE (-3400 3200);
DISPLAY INVISIBLE (-3400 3200);
FORCEPROP 1 LAST COMMENT_BODY TRUE
J 0
(-3275 3100);
DISPLAY 1.170213 (-3275 3100);
PAINT GREEN (-3275 3100);
DISPLAY INVISIBLE (-3275 3100);
FORCEPROP 1 LAST OFFPAGE TRUE
J 0
(-3075 3075);
PAINT GREEN (-3075 3075);
DISPLAY INVISIBLE (-3075 3075);
FORCEADD RES..1
(2950 3100);
FORCEPROP 1 LAST WATTAGE 1/16W
J 2
(2825 3000);
DISPLAY 0.617021 (2825 3000);
PAINT SKYBLUE (2825 3000);
FORCEPROP 1 LAST MATERIAL CHIP
J 0
(2850 3000);
DISPLAY 0.617021 (2850 3000);
PAINT SKYBLUE (2850 3000);
FORCEPROP 1 LAST VALUE 33.2
J 2
(2900 3050);
DISPLAY 0.617021 (2900 3050);
PAINT SKYBLUE (2900 3050);
FORCEPROP 1 LAST TOLERANCE 1%
J 0
(2925 3050);
DISPLAY 0.617021 (2925 3050);
PAINT SKYBLUE (2925 3050);
FORCEPROP 1 LASTPIN (2850 3100) $PN 1
J 0
(2862 3112);
DISPLAY 0.617021 (2862 3112);
PAINT ORANGE (2862 3112);
FORCEPROP 1 LAST LOCATION R2T33
J 0
(2900 3150);
DISPLAY 0.617021 (2900 3150);
PAINT AQUA (2900 3150);
FORCEPROP 1 LASTPIN (3050 3100) $PN 2
J 0
(3012 3112);
DISPLAY 0.617021 (3012 3112);
PAINT ORANGE (3012 3112);
FORCEPROP 1 LAST PART_NUMBER G21796-074
J 0
(2950 3000);
DISPLAY 0.617021 (2950 3000);
PAINT BLUE (2950 3000);
FORCEPROP 1 LAST PACK_TYPE 0402
J 0
(3000 3050);
DISPLAY 0.617021 (3000 3050);
PAINT SKYBLUE (3000 3050);
FORCEPROP 2 LAST ROOM PROC_SIDEBAND
J 0
(2875 3025);
DISPLAY 0.617021 (2875 3025);
PAINT ORANGE (2875 3025);
DISPLAY INVISIBLE (2875 3025);
FORCEPROP 2 LAST CDS_LOCATION R2T33
J 0
(2900 3150);
DISPLAY 0.617021 (2900 3150);
PAINT AQUA (2900 3150);
DISPLAY INVISIBLE (2900 3150);
FORCEPROP 1 LAST PATH I40
J 0
(2900 3250);
DISPLAY 0.978723 (2900 3250);
PAINT WHITE (2900 3250);
DISPLAY INVISIBLE (2900 3250);
FORCEPROP 2 LAST CDS_LIB mstr_discrete
J 0
(2950 3100);
PAINT ORANGE (2950 3100);
DISPLAY INVISIBLE (2950 3100);
FORCEPROP 2 LAST BOM_COST PROC
J 2
(2950 3100);
PAINT MONO (2950 3100);
DISPLAY INVISIBLE (2950 3100);
FORCEPROP 2 LAST SEC_TYPE 0402
J 0
(2900 3300);
DISPLAY 1.021277 (2900 3300);
PAINT ORANGE (2900 3300);
DISPLAY INVISIBLE (2900 3300);
FORCEPROP 2 LAST SEC 1
J 0
(2900 3300);
DISPLAY 0.680851 (2900 3300);
PAINT MONO (2900 3300);
DISPLAY INVISIBLE (2900 3300);
FORCEADD RES..1
(2950 3350);
FORCEPROP 1 LAST VALUE 33.2
J 2
(2900 3300);
DISPLAY 0.617021 (2900 3300);
PAINT SKYBLUE (2900 3300);
FORCEPROP 1 LAST WATTAGE 1/16W
J 2
(2825 3250);
DISPLAY 0.617021 (2825 3250);
PAINT SKYBLUE (2825 3250);
FORCEPROP 1 LAST MATERIAL CHIP
J 0
(2850 3250);
DISPLAY 0.617021 (2850 3250);
PAINT SKYBLUE (2850 3250);
FORCEPROP 1 LAST TOLERANCE 1%
J 0
(2925 3300);
DISPLAY 0.617021 (2925 3300);
PAINT SKYBLUE (2925 3300);
FORCEPROP 1 LASTPIN (2850 3350) $PN 1
J 0
(2862 3362);
DISPLAY 0.617021 (2862 3362);
PAINT ORANGE (2862 3362);
FORCEPROP 1 LAST LOCATION R2T30
J 0
(2900 3400);
DISPLAY 0.617021 (2900 3400);
PAINT AQUA (2900 3400);
FORCEPROP 1 LASTPIN (3050 3350) $PN 2
J 0
(3012 3362);
DISPLAY 0.617021 (3012 3362);
PAINT ORANGE (3012 3362);
FORCEPROP 1 LAST PART_NUMBER G21796-074
J 0
(2950 3250);
DISPLAY 0.617021 (2950 3250);
PAINT BLUE (2950 3250);
FORCEPROP 1 LAST PACK_TYPE 0402
J 0
(3000 3300);
DISPLAY 0.617021 (3000 3300);
PAINT SKYBLUE (3000 3300);
FORCEPROP 2 LAST ROOM PROC_SIDEBAND
J 0
(2875 3275);
DISPLAY 0.617021 (2875 3275);
PAINT ORANGE (2875 3275);
DISPLAY INVISIBLE (2875 3275);
FORCEPROP 2 LAST SEC 1
J 0
(2900 3550);
DISPLAY 0.680851 (2900 3550);
PAINT MONO (2900 3550);
DISPLAY INVISIBLE (2900 3550);
FORCEPROP 2 LAST CDS_LOCATION R2T30
J 0
(2900 3400);
DISPLAY 0.617021 (2900 3400);
PAINT AQUA (2900 3400);
DISPLAY INVISIBLE (2900 3400);
FORCEPROP 1 LAST PATH I42
J 0
(2900 3500);
DISPLAY 0.978723 (2900 3500);
PAINT WHITE (2900 3500);
DISPLAY INVISIBLE (2900 3500);
FORCEPROP 2 LAST BOM_COST PROC
J 2
(2950 3350);
PAINT MONO (2950 3350);
DISPLAY INVISIBLE (2950 3350);
FORCEPROP 2 LAST CDS_LIB mstr_discrete
J 0
(2950 3350);
PAINT ORANGE (2950 3350);
DISPLAY INVISIBLE (2950 3350);
FORCEPROP 2 LAST SEC_TYPE 0402
J 0
(2900 3550);
DISPLAY 1.021277 (2900 3550);
PAINT ORANGE (2900 3550);
DISPLAY INVISIBLE (2900 3550);
FORCEADD OFFPAGE..5
R 2
(3650 3100);
FORCEPROP 2 LAST $XR0 93 
J 0
(3839 3100);
DISPLAY 0.638298 (3839 3100);
PAINT MONO (3839 3100);
FORCEPROP 1 LAST OFFPAGE TRUE
J 2
(3325 2975);
PAINT GREEN (3325 2975);
DISPLAY INVISIBLE (3325 2975);
FORCEPROP 1 LAST COMMENT_BODY TRUE
J 2
(3550 3025);
DISPLAY 1.170213 (3550 3025);
PAINT GREEN (3550 3025);
DISPLAY INVISIBLE (3550 3025);
FORCEPROP 2 LAST CDS_LIB mstr_standard
J 0
(3650 3100);
PAINT ORANGE (3650 3100);
DISPLAY INVISIBLE (3650 3100);
FORCEPROP 2 LAST PATH I47
J 0
(3850 3150);
DISPLAY 1.021277 (3850 3150);
PAINT ORANGE (3850 3150);
DISPLAY INVISIBLE (3850 3150);
FORCEADD OFFPAGE..2
(3650 3350);
FORCEPROP 2 LAST $XR0 93 
J 0
(3839 3350);
DISPLAY 0.638298 (3839 3350);
PAINT MONO (3839 3350);
FORCEPROP 1 LAST COMMENT_BODY TRUE
J 0
(3605 3255);
DISPLAY 1.085106 (3605 3255);
PAINT GREEN (3605 3255);
DISPLAY INVISIBLE (3605 3255);
FORCEPROP 2 LAST CDS_LIB mstr_standard
J 0
(3650 3350);
PAINT MONO (3650 3350);
DISPLAY INVISIBLE (3650 3350);
FORCEPROP 2 LAST PATH I48
J 0
(3850 3400);
DISPLAY 1.021277 (3850 3400);
PAINT ORANGE (3850 3400);
DISPLAY INVISIBLE (3850 3400);
FORCEPROP 1 LAST OFFPAGE TRUE
J 0
(3975 3225);
PAINT GREEN (3975 3225);
DISPLAY INVISIBLE (3975 3225);
FORCEADD OFFPAGE..1
(-3400 3725);
FORCEPROP 2 LAST $XR0 55 
J 0
(-3621 3725);
DISPLAY 0.638298 (-3621 3725);
PAINT MONO (-3621 3725);
FORCEPROP 2 LAST PATH I5
J 0
(-3650 3775);
DISPLAY 1.021277 (-3650 3775);
PAINT ORANGE (-3650 3775);
DISPLAY INVISIBLE (-3650 3775);
FORCEPROP 2 LAST CDS_LIB mstr_standard
J 0
(-3400 3725);
PAINT ORANGE (-3400 3725);
DISPLAY INVISIBLE (-3400 3725);
FORCEPROP 1 LAST COMMENT_BODY TRUE
J 0
(-3275 3625);
DISPLAY 1.170213 (-3275 3625);
PAINT GREEN (-3275 3625);
DISPLAY INVISIBLE (-3275 3625);
FORCEPROP 1 LAST OFFPAGE TRUE
J 0
(-3075 3600);
PAINT GREEN (-3075 3600);
DISPLAY INVISIBLE (-3075 3600);
FORCEADD OFFPAGE..1
(-3400 3425);
FORCEPROP 2 LAST $XR0 21 
J 0
(-3621 3425);
DISPLAY 0.638298 (-3621 3425);
PAINT MONO (-3621 3425);
FORCEPROP 2 LAST PATH I6
J 0
(-3600 3475);
DISPLAY 1.021277 (-3600 3475);
PAINT ORANGE (-3600 3475);
DISPLAY INVISIBLE (-3600 3475);
FORCEPROP 2 LAST CDS_LIB mstr_standard
J 0
(-3400 3425);
PAINT ORANGE (-3400 3425);
DISPLAY INVISIBLE (-3400 3425);
FORCEPROP 1 LAST COMMENT_BODY TRUE
J 0
(-3275 3325);
DISPLAY 1.170213 (-3275 3325);
PAINT GREEN (-3275 3325);
DISPLAY INVISIBLE (-3275 3325);
FORCEPROP 1 LAST OFFPAGE TRUE
J 0
(-3075 3300);
PAINT GREEN (-3075 3300);
DISPLAY INVISIBLE (-3075 3300);
FORCEADD RES..1
(2950 2575);
FORCEPROP 1 LAST VALUE 33.2
J 2
(2900 2525);
DISPLAY 0.617021 (2900 2525);
PAINT SKYBLUE (2900 2525);
FORCEPROP 1 LAST TOLERANCE 1%
J 0
(2925 2525);
DISPLAY 0.617021 (2925 2525);
PAINT SKYBLUE (2925 2525);
FORCEPROP 1 LAST MATERIAL CHIP
J 0
(2850 2475);
DISPLAY 0.617021 (2850 2475);
PAINT SKYBLUE (2850 2475);
FORCEPROP 1 LAST WATTAGE 1/16W
J 2
(2825 2475);
DISPLAY 0.617021 (2825 2475);
PAINT SKYBLUE (2825 2475);
FORCEPROP 1 LASTPIN (2850 2575) $PN 1
J 0
(2862 2587);
DISPLAY 0.617021 (2862 2587);
PAINT ORANGE (2862 2587);
FORCEPROP 1 LAST LOCATION R7D24
J 0
(2900 2625);
DISPLAY 0.617021 (2900 2625);
PAINT AQUA (2900 2625);
FORCEPROP 1 LASTPIN (3050 2575) $PN 2
J 0
(3012 2587);
DISPLAY 0.617021 (3012 2587);
PAINT ORANGE (3012 2587);
FORCEPROP 1 LAST PART_NUMBER G21796-074
J 0
(2950 2475);
DISPLAY 0.617021 (2950 2475);
PAINT BLUE (2950 2475);
FORCEPROP 1 LAST PACK_TYPE 0402
J 0
(3000 2525);
DISPLAY 0.617021 (3000 2525);
PAINT SKYBLUE (3000 2525);
FORCEPROP 2 LAST ROOM PROC_SIDEBAND
J 0
(2875 2500);
DISPLAY 0.617021 (2875 2500);
PAINT ORANGE (2875 2500);
DISPLAY INVISIBLE (2875 2500);
FORCEPROP 2 LAST SEC 1
J 0
(2900 2775);
DISPLAY 0.680851 (2900 2775);
PAINT MONO (2900 2775);
DISPLAY INVISIBLE (2900 2775);
FORCEPROP 2 LAST CDS_LOCATION R7D24
J 0
(2900 2625);
DISPLAY 0.617021 (2900 2625);
PAINT AQUA (2900 2625);
DISPLAY INVISIBLE (2900 2625);
FORCEPROP 1 LAST PATH I62
J 0
(2900 2725);
DISPLAY 0.978723 (2900 2725);
PAINT WHITE (2900 2725);
DISPLAY INVISIBLE (2900 2725);
FORCEPROP 2 LAST BOM_COST PROC
J 2
(2950 2575);
PAINT MONO (2950 2575);
DISPLAY INVISIBLE (2950 2575);
FORCEPROP 2 LAST CDS_LIB mstr_discrete
J 0
(2950 2575);
PAINT ORANGE (2950 2575);
DISPLAY INVISIBLE (2950 2575);
FORCEPROP 2 LAST SEC_TYPE 0402
J 0
(2900 2775);
DISPLAY 1.021277 (2900 2775);
PAINT ORANGE (2900 2775);
DISPLAY INVISIBLE (2900 2775);
FORCEADD RES..2
(-2325 4050);
FORCEPROP 1 LASTPIN (-2325 3950) $PN 2
J 0
(-2320 3960);
DISPLAY 0.617021 (-2320 3960);
PAINT ORANGE (-2320 3960);
FORCEPROP 1 LAST WATTAGE 1/16W
J 0
(-2285 4025);
DISPLAY 0.617021 (-2285 4025);
PAINT SKYBLUE (-2285 4025);
FORCEPROP 1 LAST MATERIAL CHIP
J 0
(-2285 3975);
DISPLAY 0.617021 (-2285 3975);
PAINT SKYBLUE (-2285 3975);
FORCEPROP 1 LAST PART_NUMBER G21796-004
J 0
(-2285 3925);
DISPLAY 0.617021 (-2285 3925);
PAINT BLUE (-2285 3925);
FORCEPROP 1 LAST PACK_TYPE 0402
J 0
(-2160 3975);
DISPLAY 0.617021 (-2160 3975);
PAINT SKYBLUE (-2160 3975);
FORCEPROP 1 LAST TOLERANCE 1%
J 0
(-2280 4075);
DISPLAY 0.617021 (-2280 4075);
PAINT SKYBLUE (-2280 4075);
FORCEPROP 1 LASTPIN (-2325 4150) $PN 1
J 0
(-2320 4112);
DISPLAY 0.617021 (-2320 4112);
PAINT ORANGE (-2320 4112);
FORCEPROP 1 LAST LOCATION R2T19
J 0
(-2280 4175);
DISPLAY 0.617021 (-2280 4175);
PAINT AQUA (-2280 4175);
FORCEPROP 1 LAST VALUE 200.0
J 0
(-2280 4125);
DISPLAY 0.617021 (-2280 4125);
PAINT SKYBLUE (-2280 4125);
FORCEPROP 2 LAST CDS_LIB mstr_discrete
J 0
(-2325 4050);
PAINT MONO (-2325 4050);
DISPLAY INVISIBLE (-2325 4050);
FORCEPROP 2 LAST BOM_COST PROC
J 0
(-2325 4050);
PAINT MONO (-2325 4050);
DISPLAY INVISIBLE (-2325 4050);
FORCEPROP 2 LAST ROOM PROC_SIDEBAND
J 0
(-2300 3825);
PAINT ORANGE (-2300 3825);
DISPLAY INVISIBLE (-2300 3825);
FORCEPROP 2 LAST SEC_TYPE 0402
J 0
(-2275 4275);
DISPLAY 1.021277 (-2275 4275);
PAINT ORANGE (-2275 4275);
DISPLAY INVISIBLE (-2275 4275);
FORCEPROP 2 LAST SEC 1
J 0
(-2275 4275);
DISPLAY 0.680851 (-2275 4275);
PAINT MONO (-2275 4275);
DISPLAY INVISIBLE (-2275 4275);
FORCEPROP 2 LAST CDS_LOCATION R2T19
J 0
(-2280 4175);
DISPLAY 0.617021 (-2280 4175);
PAINT AQUA (-2280 4175);
DISPLAY INVISIBLE (-2280 4175);
FORCEPROP 1 LAST PATH I63
J 0
(-2275 4225);
DISPLAY 0.978723 (-2275 4225);
PAINT WHITE (-2275 4225);
DISPLAY INVISIBLE (-2275 4225);
FORCEADD PVCCIO_CPU0..1
(-2325 4300);
FORCEPROP 3 LASTPIN (-2325 4250) SIG_NAME PVCCIO_CPU0\g
J 0
(-2315 4260);
DISPLAY 0.659574 (-2315 4260);
PAINT MONO (-2315 4260);
DISPLAY INVISIBLE (-2315 4260);
FORCEPROP 1 LAST BODY_TYPE PLUMBING
J 0
(-2370 4257);
DISPLAY 0.340426 (-2370 4257);
PAINT GREEN (-2370 4257);
DISPLAY INVISIBLE (-2370 4257);
FORCEPROP 2 LAST CDS_LIB mstr_symbols
J 0
(-2325 4300);
PAINT ORANGE (-2325 4300);
DISPLAY INVISIBLE (-2325 4300);
FORCEPROP 1 LAST VOLTAGE 1.1V
J 0
(-2370 4257);
DISPLAY 0.340426 (-2370 4257);
PAINT SKYBLUE (-2370 4257);
DISPLAY INVISIBLE (-2370 4257);
FORCEPROP 1 LAST HDL_POWER PVCCIO_CPU0
J 1
(-2325 4350);
DISPLAY 0.872340 (-2325 4350);
PAINT GREEN (-2325 4350);
DISPLAY INVISIBLE (-2325 4350);
FORCEPROP 1 LAST PATH I64
J 0
(-2275 4325);
DISPLAY 0.872340 (-2275 4325);
PAINT AQUA (-2275 4325);
DISPLAY INVISIBLE (-2275 4325);
FORCEADD RES..1
(-925 3825);
FORCEPROP 1 LAST WATTAGE 1/16W
J 2
(-950 3675);
DISPLAY 0.617021 (-950 3675);
PAINT SKYBLUE (-950 3675);
FORCEPROP 1 LAST VALUE 75
J 2
(-950 3725);
DISPLAY 0.617021 (-950 3725);
PAINT SKYBLUE (-950 3725);
FORCEPROP 1 LAST MATERIAL CHIP
J 0
(-925 3675);
DISPLAY 0.617021 (-925 3675);
PAINT SKYBLUE (-925 3675);
FORCEPROP 1 LAST PACK_TYPE 0402
J 0
(-1000 3625);
DISPLAY 0.617021 (-1000 3625);
PAINT SKYBLUE (-1000 3625);
FORCEPROP 1 LAST TOLERANCE 1.0%
J 0
(-925 3725);
DISPLAY 0.617021 (-925 3725);
PAINT SKYBLUE (-925 3725);
FORCEPROP 1 LASTPIN (-825 3825) $PN 2
J 0
(-863 3837);
DISPLAY 0.617021 (-863 3837);
PAINT ORANGE (-863 3837);
FORCEPROP 1 LASTPIN (-1025 3825) $PN 1
J 0
(-1013 3837);
DISPLAY 0.617021 (-1013 3837);
PAINT ORANGE (-1013 3837);
FORCEPROP 1 LAST LOCATION R2T16
J 0
(-975 3875);
DISPLAY 0.617021 (-975 3875);
PAINT AQUA (-975 3875);
FORCEPROP 1 LAST PART_NUMBER G21796-267
J 0
(-900 3625);
DISPLAY 0.617021 (-900 3625);
PAINT BLUE (-900 3625);
FORCEPROP 2 LAST CDS_LIB mstr_discrete
J 0
(-925 3825);
PAINT MONO (-925 3825);
DISPLAY INVISIBLE (-925 3825);
FORCEPROP 2 LAST SEC_TYPE 0402
J 0
(-975 4025);
DISPLAY 1.021277 (-975 4025);
PAINT ORANGE (-975 4025);
DISPLAY INVISIBLE (-975 4025);
FORCEPROP 2 LAST SEC 1
J 0
(-975 4025);
DISPLAY 0.680851 (-975 4025);
PAINT MONO (-975 4025);
DISPLAY INVISIBLE (-975 4025);
FORCEPROP 2 LAST CDS_LOCATION R2T16
J 0
(-975 3875);
DISPLAY 0.617021 (-975 3875);
PAINT AQUA (-975 3875);
DISPLAY INVISIBLE (-975 3875);
FORCEPROP 1 LAST PATH I67
J 0
(-975 3975);
DISPLAY 0.978723 (-975 3975);
PAINT WHITE (-975 3975);
DISPLAY INVISIBLE (-975 3975);
FORCEPROP 0 LAST ROOM PROC_SIDEBAND
J 0
(-975 4025);
DISPLAY 1.021277 (-975 4025);
PAINT ORANGE (-975 4025);
DISPLAY INVISIBLE (-975 4025);
FORCEADD RES..1
(-925 3300);
FORCEPROP 1 LAST TOLERANCE 1.0%
J 0
(-1125 3175);
DISPLAY 0.617021 (-1125 3175);
PAINT SKYBLUE (-1125 3175);
FORCEPROP 1 LAST PACK_TYPE 0402
J 0
(-1125 3225);
DISPLAY 0.617021 (-1125 3225);
PAINT SKYBLUE (-1125 3225);
FORCEPROP 1 LAST MATERIAL CHIP
J 0
(-1075 3125);
DISPLAY 0.617021 (-1075 3125);
PAINT SKYBLUE (-1075 3125);
FORCEPROP 1 LAST WATTAGE 1/16W
J 2
(-875 3175);
DISPLAY 0.617021 (-875 3175);
PAINT SKYBLUE (-875 3175);
FORCEPROP 1 LAST VALUE 75
J 2
(-900 3225);
DISPLAY 0.617021 (-900 3225);
PAINT SKYBLUE (-900 3225);
FORCEPROP 1 LASTPIN (-825 3300) $PN 2
J 0
(-863 3312);
DISPLAY 0.617021 (-863 3312);
PAINT ORANGE (-863 3312);
FORCEPROP 1 LASTPIN (-1025 3300) $PN 1
J 0
(-1013 3312);
DISPLAY 0.617021 (-1013 3312);
PAINT ORANGE (-1013 3312);
FORCEPROP 1 LAST LOCATION R2T31
J 0
(-975 3350);
DISPLAY 0.617021 (-975 3350);
PAINT AQUA (-975 3350);
FORCEPROP 1 LAST PART_NUMBER G21796-267
J 0
(-950 3125);
DISPLAY 0.617021 (-950 3125);
PAINT BLUE (-950 3125);
FORCEPROP 2 LAST CDS_LIB mstr_discrete
J 0
(-925 3300);
PAINT MONO (-925 3300);
DISPLAY INVISIBLE (-925 3300);
FORCEPROP 0 LAST ROOM PROC_SIDEBAND
J 0
(-975 3450);
DISPLAY 1.021277 (-975 3450);
PAINT ORANGE (-975 3450);
DISPLAY INVISIBLE (-975 3450);
FORCEPROP 2 LAST SEC_TYPE 0402
J 0
(-975 3500);
DISPLAY 1.021277 (-975 3500);
PAINT ORANGE (-975 3500);
DISPLAY INVISIBLE (-975 3500);
FORCEPROP 2 LAST CDS_LOCATION R2T31
J 0
(-975 3350);
DISPLAY 0.617021 (-975 3350);
PAINT AQUA (-975 3350);
DISPLAY INVISIBLE (-975 3350);
FORCEPROP 1 LAST PATH I68
J 0
(-975 3450);
DISPLAY 0.978723 (-975 3450);
PAINT WHITE (-975 3450);
DISPLAY INVISIBLE (-975 3450);
FORCEPROP 2 LAST SEC 1
J 0
(-975 3500);
DISPLAY 0.680851 (-975 3500);
PAINT MONO (-975 3500);
DISPLAY INVISIBLE (-975 3500);
FORCEADD P3V3..1
(1000 4150);
FORCEPROP 3 LASTPIN (1000 4100) SIG_NAME P3V3\g
J 0
(1010 4110);
DISPLAY 0.659574 (1010 4110);
PAINT MONO (1010 4110);
DISPLAY INVISIBLE (1010 4110);
FORCEPROP 1 LAST HDL_POWER P3V3
J 0
(675 4025);
DISPLAY 0.872340 (675 4025);
PAINT ORANGE (675 4025);
DISPLAY INVISIBLE (675 4025);
FORCEPROP 2 LAST CDS_LIB mstr_symbols
J 0
(1000 4150);
PAINT ORANGE (1000 4150);
DISPLAY INVISIBLE (1000 4150);
FORCEPROP 1 LAST VOLTAGE 3.3V
J 0
(955 4107);
DISPLAY 0.340426 (955 4107);
PAINT SKYBLUE (955 4107);
DISPLAY INVISIBLE (955 4107);
FORCEPROP 1 LAST BODY_TYPE PLUMBING
J 0
(955 4107);
DISPLAY 0.340426 (955 4107);
PAINT GREEN (955 4107);
DISPLAY INVISIBLE (955 4107);
FORCEPROP 1 LAST SIZE 1B
J 0
(1045 4172);
DISPLAY 0.340426 (1045 4172);
PAINT GREEN (1045 4172);
DISPLAY INVISIBLE (1045 4172);
FORCEPROP 1 LAST PATH I70
J 0
(1045 4152);
DISPLAY 0.340426 (1045 4152);
PAINT GREEN (1045 4152);
DISPLAY INVISIBLE (1045 4152);
FORCEADD CAP_A..1
(1150 3875);
FORCEPROP 1 LASTPIN (1150 3775) $PN 2
J 0
(1160 3755);
DISPLAY 0.617021 (1160 3755);
PAINT MONO (1160 3755);
FORCEPROP 1 LASTPIN (1150 3975) $PN 1
J 0
(1160 3955);
DISPLAY 0.617021 (1160 3955);
PAINT MONO (1160 3955);
FORCEPROP 1 LAST LOCATION C2T33
J 0
(1200 3975);
DISPLAY 0.617021 (1200 3975);
PAINT AQUA (1200 3975);
FORCEPROP 1 LAST PART_NUMBER D97712-004
J 0
(1200 3725);
DISPLAY 0.617021 (1200 3725);
PAINT BLUE (1200 3725);
FORCEPROP 1 LAST VALUE 1.0UF
J 0
(1200 3925);
DISPLAY 0.617021 (1200 3925);
PAINT SKYBLUE (1200 3925);
FORCEPROP 1 LAST TOLERANCE 10%
J 0
(1200 3825);
DISPLAY 0.617021 (1200 3825);
PAINT SKYBLUE (1200 3825);
FORCEPROP 1 LAST PACK_TYPE 0402V
J 0
(1200 3675);
DISPLAY 0.617021 (1200 3675);
PAINT SKYBLUE (1200 3675);
FORCEPROP 1 LAST VOLTAGE 6.3V
J 0
(1200 3875);
DISPLAY 0.617021 (1200 3875);
PAINT SKYBLUE (1200 3875);
FORCEPROP 1 LAST MATERIAL X6S
J 0
(1200 3775);
DISPLAY 0.617021 (1200 3775);
PAINT SKYBLUE (1200 3775);
FORCEPROP 2 LAST ROOM PROC_SIDEBAND
J 0
(1200 3625);
PAINT ORANGE (1200 3625);
DISPLAY INVISIBLE (1200 3625);
FORCEPROP 2 LAST CDS_LOCATION C2T33
J 0
(1200 3975);
DISPLAY 0.617021 (1200 3975);
PAINT AQUA (1200 3975);
DISPLAY INVISIBLE (1200 3975);
FORCEPROP 2 LAST BOM_COST PROC
J 0
(1150 3875);
PAINT MONO (1150 3875);
DISPLAY INVISIBLE (1150 3875);
FORCEPROP 2 LAST CDS_LIB dev_discrete
J 0
(1150 3875);
PAINT ORANGE (1150 3875);
DISPLAY INVISIBLE (1150 3875);
FORCEPROP 2 LAST CDS_SEC 1
J 0
(1200 4025);
PAINT ORANGE (1200 4025);
DISPLAY INVISIBLE (1200 4025);
FORCEPROP 1 LAST PATH I72
J 0
(1200 4025);
DISPLAY 0.978723 (1200 4025);
PAINT WHITE (1200 4025);
DISPLAY INVISIBLE (1200 4025);
FORCEPROP 2 LAST SEC_TYPE 0402V
J 0
(1200 4075);
PAINT MONO (1200 4075);
DISPLAY INVISIBLE (1200 4075);
FORCEPROP 2 LAST SEC 1
J 0
(1200 4075);
DISPLAY 0.936170 (1200 4075);
PAINT MONO (1200 4075);
DISPLAY INVISIBLE (1200 4075);
FORCEADD GND..1
(1150 3675);
FORCEPROP 3 LASTPIN (1150 3725) SIG_NAME GND\g
J 0
(1160 3735);
DISPLAY 0.659574 (1160 3735);
PAINT MONO (1160 3735);
DISPLAY INVISIBLE (1160 3735);
FORCEPROP 1 LAST BODY_TYPE PLUMBING
J 0
(1105 3632);
DISPLAY 0.340426 (1105 3632);
PAINT GREEN (1105 3632);
DISPLAY INVISIBLE (1105 3632);
FORCEPROP 2 LAST CDS_LIB mstr_symbols
J 0
(1150 3675);
PAINT ORANGE (1150 3675);
DISPLAY INVISIBLE (1150 3675);
FORCEPROP 1 LAST VOLTAGE 0
J 0
(1150 3675);
PAINT SKYBLUE (1150 3675);
DISPLAY INVISIBLE (1150 3675);
FORCEPROP 1 LAST PATH I73
J 0
(1225 3675);
DISPLAY 0.872340 (1225 3675);
PAINT AQUA (1225 3675);
DISPLAY INVISIBLE (1225 3675);
FORCEPROP 1 LAST SIZE 1B
J 0
(1225 3625);
DISPLAY 1.170213 (1225 3625);
PAINT GREEN (1225 3625);
DISPLAY INVISIBLE (1225 3625);
FORCEPROP 1 LAST HDL_POWER GND
J 0
(1150 3825);
DISPLAY 1.170213 (1150 3825);
PAINT GREEN (1150 3825);
DISPLAY INVISIBLE (1150 3825);
FORCEADD OFFPAGE..5
R 2
(3650 2575);
FORCEPROP 2 LAST $XR0 93 
J 0
(3839 2575);
DISPLAY 0.638298 (3839 2575);
PAINT MONO (3839 2575);
FORCEPROP 1 LAST COMMENT_BODY TRUE
J 2
(3550 2500);
DISPLAY 1.170213 (3550 2500);
PAINT GREEN (3550 2500);
DISPLAY INVISIBLE (3550 2500);
FORCEPROP 1 LAST OFFPAGE TRUE
J 2
(3325 2450);
PAINT GREEN (3325 2450);
DISPLAY INVISIBLE (3325 2450);
FORCEPROP 2 LAST CDS_LIB mstr_standard
J 0
(3650 2575);
PAINT ORANGE (3650 2575);
DISPLAY INVISIBLE (3650 2575);
FORCEPROP 2 LAST PATH I76
J 0
(3975 2625);
DISPLAY 1.021277 (3975 2625);
PAINT ORANGE (3975 2625);
DISPLAY INVISIBLE (3975 2625);
FORCEADD OFFPAGE..5
R 2
(3650 2850);
FORCEPROP 2 LAST $XR0 93 
J 0
(3839 2850);
DISPLAY 0.638298 (3839 2850);
PAINT MONO (3839 2850);
FORCEPROP 1 LAST COMMENT_BODY TRUE
J 2
(3550 2775);
DISPLAY 1.170213 (3550 2775);
PAINT GREEN (3550 2775);
DISPLAY INVISIBLE (3550 2775);
FORCEPROP 1 LAST OFFPAGE TRUE
J 2
(3325 2725);
PAINT GREEN (3325 2725);
DISPLAY INVISIBLE (3325 2725);
FORCEPROP 2 LAST CDS_LIB mstr_standard
J 0
(3650 2850);
PAINT ORANGE (3650 2850);
DISPLAY INVISIBLE (3650 2850);
FORCEPROP 2 LAST PATH I77
J 0
(3975 2900);
DISPLAY 1.021277 (3975 2900);
PAINT ORANGE (3975 2900);
DISPLAY INVISIBLE (3975 2900);
FORCEADD PVCCIO_CPU0..1
(-2750 2800);
FORCEPROP 3 LASTPIN (-2750 2750) SIG_NAME PVCCIO_CPU0\g
J 0
(-2740 2760);
DISPLAY 0.659574 (-2740 2760);
PAINT MONO (-2740 2760);
DISPLAY INVISIBLE (-2740 2760);
FORCEPROP 1 LAST VOLTAGE 1.1V
J 0
(-2795 2757);
DISPLAY 0.340426 (-2795 2757);
PAINT SKYBLUE (-2795 2757);
DISPLAY INVISIBLE (-2795 2757);
FORCEPROP 1 LAST BODY_TYPE PLUMBING
J 0
(-2795 2757);
DISPLAY 0.340426 (-2795 2757);
PAINT GREEN (-2795 2757);
DISPLAY INVISIBLE (-2795 2757);
FORCEPROP 2 LAST CDS_LIB mstr_symbols
J 0
(-2750 2800);
PAINT ORANGE (-2750 2800);
DISPLAY INVISIBLE (-2750 2800);
FORCEPROP 1 LAST PATH I78
J 0
(-2700 2825);
DISPLAY 0.872340 (-2700 2825);
PAINT AQUA (-2700 2825);
DISPLAY INVISIBLE (-2700 2825);
FORCEPROP 1 LAST HDL_POWER PVCCIO_CPU0
J 1
(-2750 2850);
DISPLAY 0.872340 (-2750 2850);
PAINT GREEN (-2750 2850);
DISPLAY INVISIBLE (-2750 2850);
FORCEADD RES..2
(-2750 2525);
FORCEPROP 1 LAST PACK_TYPE 0402
J 0
(-2710 2350);
DISPLAY 0.617021 (-2710 2350);
PAINT SKYBLUE (-2710 2350);
FORCEPROP 1 LAST MATERIAL CHIP
J 0
(-2710 2450);
DISPLAY 0.617021 (-2710 2450);
PAINT SKYBLUE (-2710 2450);
FORCEPROP 1 LAST WATTAGE 1/16W
J 0
(-2710 2500);
DISPLAY 0.617021 (-2710 2500);
PAINT SKYBLUE (-2710 2500);
FORCEPROP 1 LASTPIN (-2750 2425) $PN 2
J 0
(-2745 2435);
DISPLAY 0.617021 (-2745 2435);
PAINT ORANGE (-2745 2435);
FORCEPROP 1 LAST TOLERANCE 1%
J 0
(-2705 2550);
DISPLAY 0.617021 (-2705 2550);
PAINT SKYBLUE (-2705 2550);
FORCEPROP 1 LASTPIN (-2750 2625) $PN 1
J 0
(-2745 2587);
DISPLAY 0.617021 (-2745 2587);
PAINT ORANGE (-2745 2587);
FORCEPROP 1 LAST LOCATION R4R3
J 0
(-2705 2650);
DISPLAY 0.617021 (-2705 2650);
PAINT AQUA (-2705 2650);
FORCEPROP 1 LAST VALUE 150.0
J 0
(-2705 2600);
DISPLAY 0.617021 (-2705 2600);
PAINT SKYBLUE (-2705 2600);
FORCEPROP 1 LAST PART_NUMBER G21796-009
J 0
(-2710 2400);
DISPLAY 0.617021 (-2710 2400);
PAINT BLUE (-2710 2400);
FORCEPROP 2 LAST ROOM PROC_SIDEBAND
J 0
(-2725 2300);
PAINT ORANGE (-2725 2300);
DISPLAY INVISIBLE (-2725 2300);
FORCEPROP 2 LAST CDS_LIB mstr_discrete
J 0
(-2750 2525);
PAINT MONO (-2750 2525);
DISPLAY INVISIBLE (-2750 2525);
FORCEPROP 2 LAST BOM_COST PROC_SIDEBAND
J 0
(-2750 2525);
PAINT MONO (-2750 2525);
DISPLAY INVISIBLE (-2750 2525);
FORCEPROP 2 LAST CDS_LOCATION R4R3
J 0
(-2705 2650);
DISPLAY 0.617021 (-2705 2650);
PAINT AQUA (-2705 2650);
DISPLAY INVISIBLE (-2705 2650);
FORCEPROP 1 LAST PATH I79
J 0
(-2700 2700);
DISPLAY 0.978723 (-2700 2700);
PAINT WHITE (-2700 2700);
DISPLAY INVISIBLE (-2700 2700);
FORCEPROP 2 LAST SEC 1
J 0
(-2700 2750);
DISPLAY 0.680851 (-2700 2750);
PAINT MONO (-2700 2750);
DISPLAY INVISIBLE (-2700 2750);
FORCEPROP 2 LAST SEC_TYPE 0402
J 0
(-2700 2750);
DISPLAY 1.021277 (-2700 2750);
PAINT ORANGE (-2700 2750);
DISPLAY INVISIBLE (-2700 2750);
FORCEADD OFFPAGE..1
(-3400 2300);
FORCEPROP 2 LAST $XR0 21 
J 0
(-3621 2300);
DISPLAY 0.638298 (-3621 2300);
PAINT MONO (-3621 2300);
FORCEPROP 2 LAST $XR1 95 
J 0
(-3711 2300);
DISPLAY 0.638298 (-3711 2300);
PAINT MONO (-3711 2300);
FORCEPROP 2 LAST PATH I81
J 0
(-3650 2350);
DISPLAY 1.021277 (-3650 2350);
PAINT ORANGE (-3650 2350);
DISPLAY INVISIBLE (-3650 2350);
FORCEPROP 2 LAST CDS_LIB mstr_standard
J 0
(-3400 2300);
PAINT ORANGE (-3400 2300);
DISPLAY INVISIBLE (-3400 2300);
FORCEPROP 1 LAST COMMENT_BODY TRUE
J 0
(-3275 2200);
DISPLAY 1.170213 (-3275 2200);
PAINT GREEN (-3275 2200);
DISPLAY INVISIBLE (-3275 2200);
FORCEPROP 1 LAST OFFPAGE TRUE
J 0
(-3075 2175);
PAINT GREEN (-3075 2175);
DISPLAY INVISIBLE (-3075 2175);
FORCEADD OFFPAGE..1
(-3400 2175);
FORCEPROP 2 LAST $XR0 55 
J 0
(-3621 2175);
DISPLAY 0.638298 (-3621 2175);
PAINT MONO (-3621 2175);
FORCEPROP 2 LAST $XR1 95 
J 0
(-3711 2175);
DISPLAY 0.638298 (-3711 2175);
PAINT MONO (-3711 2175);
FORCEPROP 2 LAST PATH I83
J 0
(-3650 2225);
DISPLAY 1.021277 (-3650 2225);
PAINT ORANGE (-3650 2225);
DISPLAY INVISIBLE (-3650 2225);
FORCEPROP 2 LAST CDS_LIB mstr_standard
J 0
(-3400 2175);
PAINT ORANGE (-3400 2175);
DISPLAY INVISIBLE (-3400 2175);
FORCEPROP 1 LAST COMMENT_BODY TRUE
J 0
(-3275 2075);
DISPLAY 1.170213 (-3275 2075);
PAINT GREEN (-3275 2075);
DISPLAY INVISIBLE (-3275 2075);
FORCEPROP 1 LAST OFFPAGE TRUE
J 0
(-3075 2050);
PAINT GREEN (-3075 2050);
DISPLAY INVISIBLE (-3075 2050);
FORCEADD RES..2
(-2025 4050);
FORCEPROP 1 LAST MATERIAL CHIP
J 0
(-1985 3975);
DISPLAY 0.617021 (-1985 3975);
PAINT SKYBLUE (-1985 3975);
FORCEPROP 1 LASTPIN (-2025 3950) $PN 2
J 0
(-2020 3960);
DISPLAY 0.617021 (-2020 3960);
PAINT ORANGE (-2020 3960);
FORCEPROP 1 LAST WATTAGE 1/16W
J 0
(-1985 4025);
DISPLAY 0.617021 (-1985 4025);
PAINT SKYBLUE (-1985 4025);
FORCEPROP 1 LAST PART_NUMBER G21796-004
J 0
(-1985 3925);
DISPLAY 0.617021 (-1985 3925);
PAINT BLUE (-1985 3925);
FORCEPROP 1 LAST PACK_TYPE 0402
J 0
(-1885 3975);
DISPLAY 0.617021 (-1885 3975);
PAINT SKYBLUE (-1885 3975);
FORCEPROP 1 LAST TOLERANCE 1%
J 0
(-1980 4075);
DISPLAY 0.617021 (-1980 4075);
PAINT SKYBLUE (-1980 4075);
FORCEPROP 1 LAST LOCATION R2T26
J 0
(-1980 4175);
DISPLAY 0.617021 (-1980 4175);
PAINT AQUA (-1980 4175);
FORCEPROP 1 LAST VALUE 200.0
J 0
(-1980 4125);
DISPLAY 0.617021 (-1980 4125);
PAINT SKYBLUE (-1980 4125);
FORCEPROP 1 LASTPIN (-2025 4150) $PN 1
J 0
(-2020 4112);
DISPLAY 0.617021 (-2020 4112);
PAINT ORANGE (-2020 4112);
FORCEPROP 2 LAST ROOM PROC_SIDEBAND
J 0
(-2000 3825);
PAINT ORANGE (-2000 3825);
DISPLAY INVISIBLE (-2000 3825);
FORCEPROP 2 LAST BOM_COST PROC
J 0
(-2025 4050);
PAINT MONO (-2025 4050);
DISPLAY INVISIBLE (-2025 4050);
FORCEPROP 2 LAST CDS_LIB mstr_discrete
J 0
(-2025 4050);
PAINT MONO (-2025 4050);
DISPLAY INVISIBLE (-2025 4050);
FORCEPROP 2 LAST SEC_TYPE 0402
J 0
(-1975 4275);
DISPLAY 1.021277 (-1975 4275);
PAINT ORANGE (-1975 4275);
DISPLAY INVISIBLE (-1975 4275);
FORCEPROP 2 LAST SEC 1
J 0
(-1975 4275);
DISPLAY 0.680851 (-1975 4275);
PAINT MONO (-1975 4275);
DISPLAY INVISIBLE (-1975 4275);
FORCEPROP 2 LAST CDS_LOCATION R2T26
J 0
(-1980 4175);
DISPLAY 0.617021 (-1980 4175);
PAINT AQUA (-1980 4175);
DISPLAY INVISIBLE (-1980 4175);
FORCEPROP 1 LAST PATH I87
J 0
(-1975 4225);
DISPLAY 0.978723 (-1975 4225);
PAINT WHITE (-1975 4225);
DISPLAY INVISIBLE (-1975 4225);
FORCEADD RES..2
(-1375 4125);
FORCEPROP 1 LASTPIN (-1375 4025) $PN 2
J 0
(-1370 4035);
DISPLAY 0.617021 (-1370 4035);
PAINT ORANGE (-1370 4035);
FORCEPROP 1 LAST MATERIAL EMPTY
J 0
(-1335 4050);
DISPLAY 0.617021 (-1335 4050);
PAINT RED (-1335 4050);
FORCEPROP 1 LAST PART_NUMBER G21497-005
J 0
(-1335 4000);
DISPLAY 0.617021 (-1335 4000);
PAINT BLUE (-1335 4000);
FORCEPROP 1 LAST PACK_TYPE 0402
J 0
(-1335 3950);
DISPLAY 0.617021 (-1335 3950);
PAINT SKYBLUE (-1335 3950);
FORCEPROP 1 LASTPIN (-1375 4225) $PN 1
J 0
(-1370 4187);
DISPLAY 0.617021 (-1370 4187);
PAINT ORANGE (-1370 4187);
FORCEPROP 1 LAST LOCATION R2T57
J 0
(-1330 4250);
DISPLAY 0.617021 (-1330 4250);
PAINT AQUA (-1330 4250);
FORCEPROP 1 LAST VALUE 0.0
J 0
(-1330 4200);
DISPLAY 0.617021 (-1330 4200);
PAINT SKYBLUE (-1330 4200);
FORCEPROP 1 LAST TOLERANCE 5%
J 0
(-1330 4150);
DISPLAY 0.617021 (-1330 4150);
PAINT SKYBLUE (-1330 4150);
FORCEPROP 1 LAST WATTAGE 1/16W
J 0
(-1335 4100);
DISPLAY 0.617021 (-1335 4100);
PAINT SKYBLUE (-1335 4100);
FORCEPROP 2 LAST CDS_LIB mstr_discrete
J 0
(-1375 4125);
PAINT ORANGE (-1375 4125);
DISPLAY INVISIBLE (-1375 4125);
FORCEPROP 1 LAST PATH I88
J 0
(-1325 4300);
DISPLAY 0.978723 (-1325 4300);
PAINT WHITE (-1325 4300);
DISPLAY INVISIBLE (-1325 4300);
FORCEPROP 2 LAST SEC_TYPE 0402
J 0
(-1325 4350);
DISPLAY 1.021277 (-1325 4350);
PAINT ORANGE (-1325 4350);
DISPLAY INVISIBLE (-1325 4350);
FORCEPROP 2 LAST SEC 1
J 0
(-1325 4350);
DISPLAY 0.680851 (-1325 4350);
PAINT MONO (-1325 4350);
DISPLAY INVISIBLE (-1325 4350);
FORCEADD RES..2
(-1100 4125);
FORCEPROP 1 LASTPIN (-1100 4025) $PN 2
J 0
(-1095 4035);
DISPLAY 0.617021 (-1095 4035);
PAINT ORANGE (-1095 4035);
FORCEPROP 1 LAST MATERIAL EMPTY
J 0
(-1060 4050);
DISPLAY 0.617021 (-1060 4050);
PAINT RED (-1060 4050);
FORCEPROP 1 LAST PART_NUMBER G21497-005
J 0
(-1060 4000);
DISPLAY 0.617021 (-1060 4000);
PAINT BLUE (-1060 4000);
FORCEPROP 1 LAST PACK_TYPE 0402
J 0
(-1060 3950);
DISPLAY 0.617021 (-1060 3950);
PAINT SKYBLUE (-1060 3950);
FORCEPROP 1 LASTPIN (-1100 4225) $PN 1
J 0
(-1095 4187);
DISPLAY 0.617021 (-1095 4187);
PAINT ORANGE (-1095 4187);
FORCEPROP 1 LAST LOCATION R2T61
J 0
(-1055 4250);
DISPLAY 0.617021 (-1055 4250);
PAINT AQUA (-1055 4250);
FORCEPROP 1 LAST VALUE 0.0
J 0
(-1055 4200);
DISPLAY 0.617021 (-1055 4200);
PAINT SKYBLUE (-1055 4200);
FORCEPROP 1 LAST TOLERANCE 5%
J 0
(-1055 4150);
DISPLAY 0.617021 (-1055 4150);
PAINT SKYBLUE (-1055 4150);
FORCEPROP 1 LAST WATTAGE 1/16W
J 0
(-1060 4100);
DISPLAY 0.617021 (-1060 4100);
PAINT SKYBLUE (-1060 4100);
FORCEPROP 2 LAST CDS_LIB mstr_discrete
J 0
(-1100 4125);
PAINT ORANGE (-1100 4125);
DISPLAY INVISIBLE (-1100 4125);
FORCEPROP 1 LAST PATH I89
J 0
(-1050 4300);
DISPLAY 0.978723 (-1050 4300);
PAINT WHITE (-1050 4300);
DISPLAY INVISIBLE (-1050 4300);
FORCEPROP 2 LAST SEC_TYPE 0402
J 0
(-1050 4350);
DISPLAY 1.021277 (-1050 4350);
PAINT ORANGE (-1050 4350);
DISPLAY INVISIBLE (-1050 4350);
FORCEPROP 2 LAST SEC 1
J 0
(-1050 4350);
DISPLAY 0.680851 (-1050 4350);
PAINT MONO (-1050 4350);
DISPLAY INVISIBLE (-1050 4350);
FORCEADD RES..2
(2025 3850);
FORCEPROP 1 LASTPIN (2025 3750) $PN 2
J 0
(2030 3760);
DISPLAY 0.617021 (2030 3760);
PAINT ORANGE (2030 3760);
FORCEPROP 1 LASTPIN (2025 3950) $PN 1
J 0
(2030 3912);
DISPLAY 0.617021 (2030 3912);
PAINT ORANGE (2030 3912);
FORCEPROP 1 LAST MATERIAL EMPTY
J 0
(2065 3775);
DISPLAY 0.617021 (2065 3775);
PAINT RED (2065 3775);
FORCEPROP 1 LAST PACK_TYPE 0402
J 0
(2065 3675);
DISPLAY 0.617021 (2065 3675);
PAINT SKYBLUE (2065 3675);
FORCEPROP 1 LAST WATTAGE 1/16W
J 0
(2065 3825);
DISPLAY 0.617021 (2065 3825);
PAINT SKYBLUE (2065 3825);
FORCEPROP 1 LAST VALUE 0.0
J 0
(2070 3925);
DISPLAY 0.617021 (2070 3925);
PAINT SKYBLUE (2070 3925);
FORCEPROP 1 LAST TOLERANCE 5%
J 0
(2070 3875);
DISPLAY 0.617021 (2070 3875);
PAINT SKYBLUE (2070 3875);
FORCEPROP 1 LAST LOCATION R2T62
J 0
(2070 3975);
DISPLAY 0.617021 (2070 3975);
PAINT AQUA (2070 3975);
FORCEPROP 1 LAST PART_NUMBER G21497-005
J 0
(2065 3725);
DISPLAY 0.617021 (2065 3725);
PAINT BLUE (2065 3725);
FORCEPROP 2 LAST CDS_LIB mstr_discrete
J 0
(2025 3850);
PAINT ORANGE (2025 3850);
DISPLAY INVISIBLE (2025 3850);
FORCEPROP 1 LAST PATH I93
J 0
(2075 4025);
DISPLAY 0.978723 (2075 4025);
PAINT WHITE (2075 4025);
DISPLAY INVISIBLE (2075 4025);
FORCEPROP 2 LAST SEC_TYPE 0402
J 0
(2075 4075);
DISPLAY 1.021277 (2075 4075);
PAINT ORANGE (2075 4075);
DISPLAY INVISIBLE (2075 4075);
FORCEPROP 2 LAST SEC 1
J 0
(2075 4075);
DISPLAY 0.680851 (2075 4075);
PAINT MONO (2075 4075);
DISPLAY INVISIBLE (2075 4075);
FORCEADD RES..2
(2400 3850);
FORCEPROP 1 LASTPIN (2400 3750) $PN 2
J 0
(2405 3760);
DISPLAY 0.617021 (2405 3760);
PAINT ORANGE (2405 3760);
FORCEPROP 1 LAST PACK_TYPE 0402
J 0
(2440 3675);
DISPLAY 0.617021 (2440 3675);
PAINT SKYBLUE (2440 3675);
FORCEPROP 1 LASTPIN (2400 3950) $PN 1
J 0
(2405 3912);
DISPLAY 0.617021 (2405 3912);
PAINT ORANGE (2405 3912);
FORCEPROP 1 LAST TOLERANCE 5%
J 0
(2445 3875);
DISPLAY 0.617021 (2445 3875);
PAINT SKYBLUE (2445 3875);
FORCEPROP 1 LAST VALUE 0.0
J 0
(2445 3925);
DISPLAY 0.617021 (2445 3925);
PAINT SKYBLUE (2445 3925);
FORCEPROP 1 LAST MATERIAL EMPTY
J 0
(2440 3775);
DISPLAY 0.617021 (2440 3775);
PAINT RED (2440 3775);
FORCEPROP 1 LAST LOCATION R2T58
J 0
(2445 3975);
DISPLAY 0.617021 (2445 3975);
PAINT AQUA (2445 3975);
FORCEPROP 1 LAST PART_NUMBER G21497-005
J 0
(2440 3725);
DISPLAY 0.617021 (2440 3725);
PAINT BLUE (2440 3725);
FORCEPROP 1 LAST WATTAGE 1/16W
J 0
(2440 3825);
DISPLAY 0.617021 (2440 3825);
PAINT SKYBLUE (2440 3825);
FORCEPROP 2 LAST CDS_LIB mstr_discrete
J 0
(2400 3850);
PAINT ORANGE (2400 3850);
DISPLAY INVISIBLE (2400 3850);
FORCEPROP 1 LAST PATH I94
J 0
(2450 4025);
DISPLAY 0.978723 (2450 4025);
PAINT WHITE (2450 4025);
DISPLAY INVISIBLE (2450 4025);
FORCEPROP 2 LAST SEC_TYPE 0402
J 0
(2450 4075);
DISPLAY 1.021277 (2450 4075);
PAINT ORANGE (2450 4075);
DISPLAY INVISIBLE (2450 4075);
FORCEPROP 2 LAST SEC 1
J 0
(2450 4075);
DISPLAY 0.680851 (2450 4075);
PAINT MONO (2450 4075);
DISPLAY INVISIBLE (2450 4075);
FORCEADD CAP_A..1
(1925 625);
FORCEPROP 1 LASTPIN (1925 525) $PN 2
J 0
(1935 505);
DISPLAY 0.617021 (1935 505);
PAINT MONO (1935 505);
FORCEPROP 1 LASTPIN (1925 725) $PN 1
J 0
(1935 705);
DISPLAY 0.617021 (1935 705);
PAINT MONO (1935 705);
FORCEPROP 1 LAST LOCATION C2T32
J 0
(1975 725);
DISPLAY 0.617021 (1975 725);
PAINT AQUA (1975 725);
FORCEPROP 1 LAST PART_NUMBER A36096-030
J 0
(1975 475);
DISPLAY 0.617021 (1975 475);
PAINT BLUE (1975 475);
FORCEPROP 1 LAST VALUE 0.1UF
J 0
(1975 675);
DISPLAY 0.617021 (1975 675);
PAINT SKYBLUE (1975 675);
FORCEPROP 1 LAST TOLERANCE 10%
J 0
(1975 575);
DISPLAY 0.617021 (1975 575);
PAINT SKYBLUE (1975 575);
FORCEPROP 1 LAST PACK_TYPE 0402V
J 0
(1975 425);
DISPLAY 0.617021 (1975 425);
PAINT SKYBLUE (1975 425);
FORCEPROP 1 LAST VOLTAGE 16V
J 0
(1975 625);
DISPLAY 0.617021 (1975 625);
PAINT SKYBLUE (1975 625);
FORCEPROP 1 LAST MATERIAL X7R
J 0
(1975 525);
DISPLAY 0.617021 (1975 525);
PAINT SKYBLUE (1975 525);
FORCEPROP 2 LAST ROOM PROC_SIDEBAND
J 0
(1975 375);
DISPLAY 0.978723 (1975 375);
PAINT ORANGE (1975 375);
DISPLAY INVISIBLE (1975 375);
FORCEPROP 2 LAST CDS_LIB dev_discrete
J 0
(1925 625);
PAINT ORANGE (1925 625);
DISPLAY INVISIBLE (1925 625);
FORCEPROP 2 LAST BOM_COST PROC
J 0
(1925 625);
PAINT MONO (1925 625);
DISPLAY INVISIBLE (1925 625);
FORCEPROP 2 LAST CDS_LOCATION C2T32
J 0
(1975 725);
DISPLAY 0.617021 (1975 725);
PAINT AQUA (1975 725);
DISPLAY INVISIBLE (1975 725);
FORCEPROP 2 LAST SEC 1
J 0
(1975 825);
DISPLAY 0.936170 (1975 825);
PAINT MONO (1975 825);
DISPLAY INVISIBLE (1975 825);
FORCEPROP 2 LAST SEC_TYPE 0402V
J 0
(1975 825);
PAINT MONO (1975 825);
DISPLAY INVISIBLE (1975 825);
FORCEPROP 2 LAST CDS_SEC 1
J 0
(1975 775);
PAINT ORANGE (1975 775);
DISPLAY INVISIBLE (1975 775);
FORCEPROP 1 LAST PATH I95
J 0
(1975 775);
DISPLAY 0.978723 (1975 775);
PAINT WHITE (1975 775);
DISPLAY INVISIBLE (1975 775);
FORCEADD PVCCIO_CPU0..1
(2275 1325);
FORCEPROP 3 LASTPIN (2275 1275) SIG_NAME PVCCIO_CPU0\g
J 0
(2285 1285);
DISPLAY 0.659574 (2285 1285);
PAINT MONO (2285 1285);
DISPLAY INVISIBLE (2285 1285);
FORCEPROP 1 LAST VOLTAGE 1.1V
J 0
(2230 1282);
DISPLAY 0.340426 (2230 1282);
PAINT SKYBLUE (2230 1282);
DISPLAY INVISIBLE (2230 1282);
FORCEPROP 2 LAST CDS_LIB mstr_symbols
J 0
(2275 1325);
PAINT ORANGE (2275 1325);
DISPLAY INVISIBLE (2275 1325);
FORCEPROP 1 LAST BODY_TYPE PLUMBING
J 0
(2230 1282);
DISPLAY 0.340426 (2230 1282);
PAINT GREEN (2230 1282);
DISPLAY INVISIBLE (2230 1282);
FORCEPROP 1 LAST HDL_POWER PVCCIO_CPU0
J 1
(2275 1375);
DISPLAY 0.872340 (2275 1375);
PAINT GREEN (2275 1375);
DISPLAY INVISIBLE (2275 1375);
FORCEPROP 1 LAST PATH I96
J 0
(2325 1350);
DISPLAY 0.872340 (2325 1350);
PAINT AQUA (2325 1350);
DISPLAY INVISIBLE (2325 1350);
FORCEADD RES..2
(2275 1100);
FORCEPROP 1 LAST PACK_TYPE 0402
J 0
(2315 925);
DISPLAY 0.617021 (2315 925);
PAINT SKYBLUE (2315 925);
FORCEPROP 1 LAST PART_NUMBER G21796-047
J 0
(2315 975);
DISPLAY 0.617021 (2315 975);
PAINT BLUE (2315 975);
FORCEPROP 1 LASTPIN (2275 1000) $PN 2
J 0
(2280 1010);
DISPLAY 0.617021 (2280 1010);
PAINT MONO (2280 1010);
FORCEPROP 1 LASTPIN (2275 1200) $PN 1
J 0
(2280 1162);
DISPLAY 0.617021 (2280 1162);
PAINT MONO (2280 1162);
FORCEPROP 1 LAST VALUE 49.9
J 0
(2320 1175);
DISPLAY 0.617021 (2320 1175);
PAINT SKYBLUE (2320 1175);
FORCEPROP 1 LAST LOCATION R2T36
J 0
(2320 1225);
DISPLAY 0.617021 (2320 1225);
PAINT AQUA (2320 1225);
FORCEPROP 1 LAST TOLERANCE 1%
J 0
(2320 1125);
DISPLAY 0.617021 (2320 1125);
PAINT SKYBLUE (2320 1125);
FORCEPROP 1 LAST MATERIAL CHIP
J 0
(2315 1025);
DISPLAY 0.617021 (2315 1025);
PAINT SKYBLUE (2315 1025);
FORCEPROP 1 LAST WATTAGE 1/16W
J 0
(2315 1075);
DISPLAY 0.617021 (2315 1075);
PAINT SKYBLUE (2315 1075);
FORCEPROP 2 LAST ROOM PROC_SIDEBAND
J 0
(2300 875);
PAINT ORANGE (2300 875);
DISPLAY INVISIBLE (2300 875);
FORCEPROP 2 LAST CDS_LIB mstr_discrete
J 0
(2275 1100);
PAINT ORANGE (2275 1100);
DISPLAY INVISIBLE (2275 1100);
FORCEPROP 2 LAST BOM_COST PROC
J 0
(2275 1100);
PAINT MONO (2275 1100);
DISPLAY INVISIBLE (2275 1100);
FORCEPROP 2 LAST SEC 1
J 0
(2325 1325);
DISPLAY 0.680851 (2325 1325);
PAINT MONO (2325 1325);
DISPLAY INVISIBLE (2325 1325);
FORCEPROP 2 LAST SEC_TYPE 0402
J 0
(2325 1325);
DISPLAY 1.021277 (2325 1325);
PAINT ORANGE (2325 1325);
DISPLAY INVISIBLE (2325 1325);
FORCEPROP 1 LAST PATH I97
J 0
(2325 1275);
DISPLAY 0.978723 (2325 1275);
PAINT WHITE (2325 1275);
DISPLAY INVISIBLE (2325 1275);
FORCEPROP 2 LAST CDS_LOCATION R2T36
J 0
(2320 1225);
DISPLAY 0.617021 (2320 1225);
PAINT AQUA (2320 1225);
DISPLAY INVISIBLE (2320 1225);
FORCEADD RES..2
(2275 575);
FORCEPROP 1 LASTPIN (2275 475) $PN 2
J 0
(2280 485);
DISPLAY 0.617021 (2280 485);
PAINT MONO (2280 485);
FORCEPROP 1 LAST PACK_TYPE 0402
J 0
(2315 400);
DISPLAY 0.617021 (2315 400);
PAINT SKYBLUE (2315 400);
FORCEPROP 1 LAST MATERIAL CHIP
J 0
(2315 500);
DISPLAY 0.617021 (2315 500);
PAINT SKYBLUE (2315 500);
FORCEPROP 1 LASTPIN (2275 675) $PN 1
J 0
(2280 637);
DISPLAY 0.617021 (2280 637);
PAINT MONO (2280 637);
FORCEPROP 1 LAST TOLERANCE 1%
J 0
(2320 600);
DISPLAY 0.617021 (2320 600);
PAINT SKYBLUE (2320 600);
FORCEPROP 1 LAST VALUE 100.0
J 0
(2320 650);
DISPLAY 0.617021 (2320 650);
PAINT SKYBLUE (2320 650);
FORCEPROP 1 LAST WATTAGE 1/16W
J 0
(2315 550);
DISPLAY 0.617021 (2315 550);
PAINT SKYBLUE (2315 550);
FORCEPROP 1 LAST LOCATION R2T39
J 0
(2320 700);
DISPLAY 0.617021 (2320 700);
PAINT AQUA (2320 700);
FORCEPROP 1 LAST PART_NUMBER G21796-017
J 0
(2315 450);
DISPLAY 0.617021 (2315 450);
PAINT BLUE (2315 450);
FORCEPROP 2 LAST CDS_LIB mstr_discrete
J 2
(2275 575);
PAINT ORANGE (2275 575);
DISPLAY INVISIBLE (2275 575);
FORCEPROP 2 LAST BOM_COST PROC
J 0
(2275 575);
PAINT MONO (2275 575);
DISPLAY INVISIBLE (2275 575);
FORCEPROP 2 LAST CDS_LOCATION R2T39
J 0
(2320 700);
DISPLAY 0.617021 (2320 700);
PAINT AQUA (2320 700);
DISPLAY INVISIBLE (2320 700);
FORCEPROP 1 LAST PATH I98
J 0
(2325 750);
DISPLAY 0.978723 (2325 750);
PAINT WHITE (2325 750);
DISPLAY INVISIBLE (2325 750);
FORCEPROP 2 LAST SEC_TYPE 0402
J 0
(2325 800);
DISPLAY 1.021277 (2325 800);
PAINT ORANGE (2325 800);
DISPLAY INVISIBLE (2325 800);
FORCEPROP 2 LAST SEC 1
J 0
(2325 800);
DISPLAY 0.680851 (2325 800);
PAINT MONO (2325 800);
DISPLAY INVISIBLE (2325 800);
FORCEPROP 2 LAST ROOM PROC_SIDEBAND
J 2
(2575 350);
DISPLAY 0.978723 (2575 350);
PAINT ORANGE (2575 350);
DISPLAY INVISIBLE (2575 350);
FORCEADD GND..1
(2275 225);
FORCEPROP 3 LASTPIN (2275 275) SIG_NAME GND\g
J 0
(2285 285);
DISPLAY 0.659574 (2285 285);
PAINT MONO (2285 285);
DISPLAY INVISIBLE (2285 285);
FORCEPROP 1 LAST BODY_TYPE PLUMBING
J 0
(2230 182);
DISPLAY 0.340426 (2230 182);
PAINT GREEN (2230 182);
DISPLAY INVISIBLE (2230 182);
FORCEPROP 1 LAST VOLTAGE 0
J 0
(2275 225);
PAINT SKYBLUE (2275 225);
DISPLAY INVISIBLE (2275 225);
FORCEPROP 2 LAST CDS_LIB mstr_symbols
J 0
(2275 225);
PAINT ORANGE (2275 225);
DISPLAY INVISIBLE (2275 225);
FORCEPROP 1 LAST HDL_POWER GND
J 0
(2275 375);
DISPLAY 1.212766 (2275 375);
PAINT GREEN (2275 375);
DISPLAY INVISIBLE (2275 375);
FORCEPROP 1 LAST PATH I99
J 0
(2350 225);
DISPLAY 0.872340 (2350 225);
PAINT AQUA (2350 225);
DISPLAY INVISIBLE (2350 225);
FORCEPROP 1 LAST SIZE 1B
J 0
(2350 175);
DISPLAY 1.212766 (2350 175);
PAINT GREEN (2350 175);
DISPLAY INVISIBLE (2350 175);
FORCEADD CAD_NOTE..1
(1175 2275);
FORCEPROP 0 LAST L1 USE SHARED PADS FOR 0OHM
J 0
(1025 2175);
DISPLAY 0.617021 (1025 2175);
PAINT WHITE (1025 2175);
FORCEPROP 0 LAST L2 STEERING RESISTORS
J 0
(1025 2125);
DISPLAY 0.638298 (1025 2125);
PAINT ORANGE (1025 2125);
FORCEPROP 2 LAST CDS_LIB mstr_symbols
J 0
(1175 2275);
PAINT ORANGE (1175 2275);
DISPLAY INVISIBLE (1175 2275);
FORCEPROP 1 LAST COMMENT_BODY TRUE
J 0
(1200 2375);
DISPLAY 1.319149 (1200 2375);
PAINT WHITE (1200 2375);
DISPLAY INVISIBLE (1200 2375);
FORCEADD DNS..2
(2405 3845);
PAINT RED (2405 3845);
FORCEPROP 1 LAST COMMENT_BODY TRUE
R 1
J 0
(2480 3620);
DISPLAY 0.872340 (2480 3620);
PAINT GREEN (2480 3620);
DISPLAY INVISIBLE (2480 3620);
FORCEPROP 2 LAST CDS_LIB mstr_misc
J 0
(2405 3845);
PAINT ORANGE (2405 3845);
DISPLAY INVISIBLE (2405 3845);
FORCEADD DESIGN_NOTE..1
(225 2800);
PAINT PURPLE (225 2800);
FORCEPROP 0 LAST L3 VREF IS SET AT 2/3 OF VCCIO
J 0
(25 2575);
DISPLAY 0.808511 (25 2575);
PAINT VIOLET (25 2575);
FORCEPROP 0 LAST L2 THE PINS 'BX' ARE INPUTS & 'AX' OUTPUTS ARE PUSH-PULL.
J 0
(25 2625);
DISPLAY 0.808511 (25 2625);
PAINT VIOLET (25 2625);
FORCEPROP 0 LAST L1 THE GTL2014 IS BEING USED AS GTL TO LVTTL CONVERTER, SO
J 0
(25 2675);
DISPLAY 0.808511 (25 2675);
PAINT VIOLET (25 2675);
FORCEPROP 2 LAST CDS_LIB mstr_symbols
J 0
(225 2800);
PAINT ORANGE (225 2800);
DISPLAY INVISIBLE (225 2800);
FORCEPROP 2 LAST BOM_COST SM_CONTROLLER
J 0
(25 2750);
PAINT MONO (25 2750);
DISPLAY INVISIBLE (25 2750);
FORCEPROP 1 LAST COMMENT_BODY TRUE
J 0
(250 2900);
DISPLAY 1.319149 (250 2900);
PAINT GREEN (250 2900);
DISPLAY INVISIBLE (250 2900);
FORCEPROP 2 LAST ROOM PVCCIN_CPU1_DECAP_VR
J 0
(25 2750);
PAINT MONO (25 2750);
DISPLAY INVISIBLE (25 2750);
FORCEADD CAD_NOTE..1
(2900 2350);
FORCEPROP 0 LAST L1 USE SHARED PADS WITH 0OHM
J 0
(2750 2250);
DISPLAY 0.617021 (2750 2250);
PAINT WHITE (2750 2250);
FORCEPROP 0 LAST L2 STEERING RESISTORS
J 0
(2750 2200);
DISPLAY 0.638298 (2750 2200);
PAINT ORANGE (2750 2200);
FORCEPROP 2 LAST CDS_LIB mstr_symbols
J 0
(2900 2350);
PAINT ORANGE (2900 2350);
DISPLAY INVISIBLE (2900 2350);
FORCEPROP 1 LAST COMMENT_BODY TRUE
J 0
(2925 2450);
DISPLAY 1.319149 (2925 2450);
PAINT WHITE (2925 2450);
DISPLAY INVISIBLE (2925 2450);
FORCEADD DNS..2
(2030 2220);
PAINT RED (2030 2220);
FORCEPROP 1 LAST COMMENT_BODY TRUE
R 1
J 0
(2105 1995);
DISPLAY 0.872340 (2105 1995);
PAINT GREEN (2105 1995);
DISPLAY INVISIBLE (2105 1995);
FORCEPROP 2 LAST CDS_LIB mstr_misc
J 0
(2030 2220);
PAINT ORANGE (2030 2220);
DISPLAY INVISIBLE (2030 2220);
FORCEADD DNS..2
(-1395 1895);
PAINT RED (-1395 1895);
FORCEPROP 1 LAST COMMENT_BODY TRUE
R 1
J 0
(-1320 1670);
DISPLAY 0.872340 (-1320 1670);
PAINT GREEN (-1320 1670);
DISPLAY INVISIBLE (-1320 1670);
FORCEPROP 2 LAST CDS_LIB mstr_misc
J 0
(-1395 1895);
PAINT ORANGE (-1395 1895);
DISPLAY INVISIBLE (-1395 1895);
FORCEADD DNS..2
(-2220 1245);
PAINT RED (-2220 1245);
FORCEPROP 1 LAST COMMENT_BODY TRUE
R 1
J 0
(-2145 1020);
DISPLAY 0.872340 (-2145 1020);
PAINT GREEN (-2145 1020);
DISPLAY INVISIBLE (-2145 1020);
FORCEPROP 2 LAST CDS_LIB mstr_misc
J 0
(-2220 1245);
PAINT ORANGE (-2220 1245);
DISPLAY INVISIBLE (-2220 1245);
FORCEADD DNS..2
(-2220 845);
PAINT RED (-2220 845);
FORCEPROP 1 LAST COMMENT_BODY TRUE
R 1
J 0
(-2145 620);
DISPLAY 0.872340 (-2145 620);
PAINT GREEN (-2145 620);
DISPLAY INVISIBLE (-2145 620);
FORCEPROP 2 LAST CDS_LIB mstr_misc
J 0
(-2220 845);
PAINT ORANGE (-2220 845);
DISPLAY INVISIBLE (-2220 845);
FORCEADD CAD_NOTE..1
(-2775 4550);
FORCEPROP 0 LAST L1 PLACE ALL COMPONENTS NEAR GTL CONVERTER
J 0
(-2925 4450);
DISPLAY 0.808511 (-2925 4450);
PAINT ORANGE (-2925 4450);
FORCEPROP 2 LAST ROOM BMC
J 0
(-2925 4500);
PAINT WHITE (-2925 4500);
DISPLAY INVISIBLE (-2925 4500);
FORCEPROP 2 LAST BOM_COST SM_CONTROLLER
J 0
(-2925 4500);
PAINT WHITE (-2925 4500);
DISPLAY INVISIBLE (-2925 4500);
FORCEPROP 2 LAST CDS_LIB mstr_symbols
J 0
(-2775 4550);
PAINT WHITE (-2775 4550);
DISPLAY INVISIBLE (-2775 4550);
FORCEPROP 1 LAST COMMENT_BODY TRUE
J 0
(-2750 4650);
DISPLAY 1.319149 (-2750 4650);
PAINT WHITE (-2750 4650);
DISPLAY INVISIBLE (-2750 4650);
FORCEADD CAD_NOTE..1
(-2625 2000);
FORCEPROP 0 LAST L1 PLACE ONE 150 OHM PU RESISTOR NEAR CPU
J 0
(-2775 1900);
DISPLAY 0.808511 (-2775 1900);
PAINT ORANGE (-2775 1900);
FORCEPROP 0 LAST L2 THE OTHER NEAR GTL2014 FOR EACH SIGNAL
J 0
(-2775 1825);
DISPLAY 0.808511 (-2775 1825);
PAINT ORANGE (-2775 1825);
FORCEPROP 2 LAST CDS_LIB mstr_symbols
J 0
(-2625 2000);
PAINT WHITE (-2625 2000);
DISPLAY INVISIBLE (-2625 2000);
FORCEPROP 1 LAST COMMENT_BODY TRUE
J 0
(-2600 2100);
DISPLAY 1.319149 (-2600 2100);
PAINT WHITE (-2600 2100);
DISPLAY INVISIBLE (-2600 2100);
FORCEADD DESIGN_NOTE..1
(-200 1550);
FORCEPROP 1 LAST COMMENT_BODY TRUE
J 0
(-175 1650);
DISPLAY 0.978723 (-175 1650);
PAINT ORANGE (-175 1650);
DISPLAY INVISIBLE (-175 1650);
FORCEPROP 2 LAST CDS_LIB mstr_symbols
J 0
(-200 1550);
PAINT ORANGE (-200 1550);
DISPLAY INVISIBLE (-200 1550);
FORCEADD DNS..2
(-2220 470);
PAINT RED (-2220 470);
FORCEPROP 1 LAST COMMENT_BODY TRUE
R 1
J 0
(-2145 245);
DISPLAY 0.872340 (-2145 245);
PAINT GREEN (-2145 245);
DISPLAY INVISIBLE (-2145 245);
FORCEPROP 2 LAST CDS_LIB mstr_misc
J 0
(-2220 470);
PAINT ORANGE (-2220 470);
DISPLAY INVISIBLE (-2220 470);
FORCEADD DNS..2
(2405 2220);
PAINT RED (2405 2220);
FORCEPROP 1 LAST COMMENT_BODY TRUE
R 1
J 0
(2480 1995);
DISPLAY 0.872340 (2480 1995);
PAINT GREEN (2480 1995);
DISPLAY INVISIBLE (2480 1995);
FORCEPROP 2 LAST CDS_LIB mstr_misc
J 0
(2405 2220);
PAINT ORANGE (2405 2220);
DISPLAY INVISIBLE (2405 2220);
FORCEADD DNS..2
(-2220 70);
PAINT RED (-2220 70);
FORCEPROP 1 LAST COMMENT_BODY TRUE
R 1
J 0
(-2145 -155);
DISPLAY 0.872340 (-2145 -155);
PAINT GREEN (-2145 -155);
DISPLAY INVISIBLE (-2145 -155);
FORCEPROP 2 LAST CDS_LIB mstr_misc
J 0
(-2220 70);
PAINT ORANGE (-2220 70);
DISPLAY INVISIBLE (-2220 70);
FORCEADD DNS..2
(-1095 1895);
PAINT RED (-1095 1895);
FORCEPROP 1 LAST COMMENT_BODY TRUE
R 1
J 0
(-1020 1670);
DISPLAY 0.872340 (-1020 1670);
PAINT GREEN (-1020 1670);
DISPLAY INVISIBLE (-1020 1670);
FORCEPROP 2 LAST CDS_LIB mstr_misc
J 0
(-1095 1895);
PAINT ORANGE (-1095 1895);
DISPLAY INVISIBLE (-1095 1895);
FORCEADD DNS..2
(-1370 4120);
PAINT RED (-1370 4120);
FORCEPROP 1 LAST COMMENT_BODY TRUE
R 1
J 0
(-1295 3895);
DISPLAY 0.872340 (-1295 3895);
PAINT GREEN (-1295 3895);
DISPLAY INVISIBLE (-1295 3895);
FORCEPROP 2 LAST CDS_LIB mstr_misc
J 0
(-1370 4120);
PAINT ORANGE (-1370 4120);
DISPLAY INVISIBLE (-1370 4120);
FORCEADD DNS..2
(-1095 4120);
PAINT RED (-1095 4120);
FORCEPROP 1 LAST COMMENT_BODY TRUE
R 1
J 0
(-1020 3895);
DISPLAY 0.872340 (-1020 3895);
PAINT GREEN (-1020 3895);
DISPLAY INVISIBLE (-1020 3895);
FORCEPROP 2 LAST CDS_LIB mstr_misc
J 0
(-1095 4120);
PAINT ORANGE (-1095 4120);
DISPLAY INVISIBLE (-1095 4120);
FORCEADD DNS..2
(2030 3845);
PAINT RED (2030 3845);
FORCEPROP 1 LAST COMMENT_BODY TRUE
R 1
J 0
(2105 3620);
DISPLAY 0.872340 (2105 3620);
PAINT GREEN (2105 3620);
DISPLAY INVISIBLE (2105 3620);
FORCEPROP 2 LAST CDS_LIB mstr_misc
J 0
(2030 3845);
PAINT ORANGE (2030 3845);
DISPLAY INVISIBLE (2030 3845);
FORCEADD CAD_NOTE..1
(-325 2350);
FORCEPROP 0 LAST L1 USE SHARED PADS
J 0
(-475 2250);
DISPLAY 0.617021 (-475 2250);
PAINT WHITE (-475 2250);
FORCEPROP 0 LAST L2 FOR RESISTORS
J 0
(-475 2200);
DISPLAY 0.638298 (-475 2200);
PAINT ORANGE (-475 2200);
FORCEPROP 2 LAST CDS_LIB mstr_symbols
J 0
(-325 2350);
PAINT ORANGE (-325 2350);
DISPLAY INVISIBLE (-325 2350);
FORCEPROP 1 LAST COMMENT_BODY TRUE
J 0
(-300 2450);
DISPLAY 1.319149 (-300 2450);
PAINT WHITE (-300 2450);
DISPLAY INVISIBLE (-300 2450);
FORCEADD CAD_NOTE..1
(-1775 -50);
FORCEPROP 0 LAST L2 33.2OHM RESISTORS
J 0
(-1925 -200);
DISPLAY 0.638298 (-1925 -200);
PAINT ORANGE (-1925 -200);
FORCEPROP 0 LAST L1 USE SHARED PADS WITH
J 0
(-1925 -150);
DISPLAY 0.617021 (-1925 -150);
PAINT WHITE (-1925 -150);
FORCEPROP 2 LAST CDS_LIB mstr_symbols
J 0
(-1775 -50);
PAINT ORANGE (-1775 -50);
DISPLAY INVISIBLE (-1775 -50);
FORCEPROP 1 LAST COMMENT_BODY TRUE
J 0
(-1750 50);
DISPLAY 1.319149 (-1750 50);
PAINT WHITE (-1750 50);
DISPLAY INVISIBLE (-1750 50);
FORCEADD INTEL_CORP_BPAGE..1
(4200 -325);
FORCEPROP 1 LAST CDS_CON_LAST_MODIFIED Tue Dec 01 11:51:48 2015
J 0
(2775 0);
PAINT ORANGE (2775 0);
DISPLAY INVISIBLE (2775 0);
FORCEPROP 1 LAST CUSTOM_TXT_CDS <CURRENT_DESIGN_SHEET> OF <TOTAL_DESIGN_SHEETS>
J 0
(3700 -300);
PAINT GREEN (3700 -300);
FORCEPROP 1 LAST CUSTOM_TXT_CDS <CON_LAST_MODIFIED>
J 0
(2275 25);
PAINT GREEN (2275 25);
FORCEPROP 2 LAST CUSTOM_TXT_CDS <XR_PAGE_TITLE>
J 0
(-3690 4925);
DISPLAY 0.638298 (-3690 4925);
PAINT PINK (-3690 4925);
DISPLAY INVISIBLE (-3690 4925);
FORCEPROP 1 LAST SCH_TITLE ERRORS CIRCUITRY
J 0
(-3750 -275);
DISPLAY 1.212766 (-3750 -275);
PAINT ORANGE (-3750 -275);
FORCEPROP 1 LAST SCH_ADDRESS1 2200 Mission College Blvd.
J 0
(225 -200);
DISPLAY 0.617021 (225 -200);
PAINT GREEN (225 -200);
FORCEPROP 1 LAST SCH_ADDRESS3 Santa Clara, CA 95052-8119
J 0
(225 -300);
DISPLAY 0.617021 (225 -300);
PAINT GREEN (225 -300);
FORCEPROP 1 LAST SCH_ADDRESS2 P.O. BOX 58119
J 0
(225 -250);
DISPLAY 0.617021 (225 -250);
PAINT GREEN (225 -250);
FORCEPROP 1 LAST SCH_NUMBER H4694802
J 0
(2900 -175);
DISPLAY 1.212766 (2900 -175);
PAINT YELLOW (2900 -175);
FORCEPROP 1 LAST SCH_DEPT BESD
J 1
(-250 -225);
DISPLAY 1.212766 (-250 -225);
PAINT YELLOW (-250 -225);
FORCEPROP 1 LAST SCH_REV 2.420
J 0
(3950 -175);
DISPLAY 0.978723 (3950 -175);
PAINT YELLOW (3950 -175);
FORCEPROP 2 LAST PAGE_BORDER TRUE
J 0
(-3690 4925);
DISPLAY 0.638298 (-3690 4925);
PAINT PINK (-3690 4925);
DISPLAY INVISIBLE (-3690 4925);
FORCEPROP 2 LAST CDS_LIB mstr_symbols
J 0
(4200 -325);
PAINT MONO (4200 -325);
DISPLAY INVISIBLE (4200 -325);
FORCEPROP 1 LAST COMMENT_BODY TRUE
J 0
(4212 -313);
DISPLAY 0.468085 (4212 -313);
PAINT GREEN (4212 -313);
DISPLAY INVISIBLE (4212 -313);
FORCEPROP 2 LAST CDS_XR_PAGE_TITLE CR-93 : @BASEBOARD_FAB2_LIB.BASEBOARD_FAB2(SCH_1):PAGE93
J 0
(-3690 4925);
DISPLAY 0.638298 (-3690 4925);
PAINT PINK (-3690 4925);
DISPLAY INVISIBLE (-3690 4925);
WIRE 16 -1 (-1900 2700)(-1900 2600);
WIRE 16 -1 (-1900 2700)(-2200 2700);
WIRE 16 -1 (-2200 2600)(-2200 2700);
WIRE 16 -1 (-2200 2700)(-2200 2750);
WIRE 16 -1 (3700 275)(3700 325);
WIRE 16 -1 (-200 3050)(-25 3050);
WIRE 16 -1 (-200 3000)(-200 3050);
WIRE 16 -1 (-25 3000)(-200 3000);
WIRE 16 -1 (-200 2950)(-200 3000);
WIRE 16 -1 (-25 2950)(-200 2950);
WIRE 16 -1 (-200 2875)(-200 2950);
WIRE 16 -1 (-2025 4225)(-2025 4150);
WIRE 16 -1 (-2325 4225)(-2025 4225);
WIRE 16 -1 (-2325 4150)(-2325 4225);
WIRE 16 -1 (-2325 4225)(-2325 4250);
WIRE 16 -1 (875 3650)(1000 3650);
WIRE 16 -1 (1000 3650)(1000 4050);
WIRE 16 -1 (1150 4050)(1000 4050);
WIRE 16 -1 (1000 4050)(1000 4100);
WIRE 16 -1 (1150 3975)(1150 4050);
WIRE 16 -1 (1150 3725)(1150 3775);
WIRE 16 -1 (-2475 2625)(-2475 2725);
WIRE 16 -1 (-2475 2725)(-2750 2725);
WIRE 16 -1 (-2750 2750)(-2750 2725);
WIRE 16 -1 (-2750 2725)(-2750 2625);
WIRE 16 -1 (2275 1200)(2275 1275);
WIRE 16 -1 (1925 525)(1925 325);
WIRE 16 -1 (1925 325)(2275 325);
WIRE 16 -1 (2275 475)(2275 325);
WIRE 16 -1 (2275 325)(2275 275);
WIRE 16 -1 (2025 4425)(2025 3950);
WIRE 16 -1 (-1100 4425)(2025 4425);
FORCEPROP 2 LAST SIG_NAME H_CPU_ERR1_PCH_N
J 0
(440 4435);
DISPLAY 0.617021 (440 4435);
PAINT ORANGE (440 4435);
FORCEPROP 2 LASTPROP $XRERR UNIQUE?
J 0
(200 4435);
DISPLAY 0.638298 (200 4435);
PAINT MONO (200 4435);
DISPLAY INVISIBLE (200 4435);
WIRE 16 -1 (-1100 4225)(-1100 4425);
WIRE 16 -1 (2400 3950)(2400 4475);
WIRE 16 -1 (2400 4475)(-1375 4475);
FORCEPROP 2 LAST SIG_NAME H_CPU_ERR0_PCH_N
J 0
(440 4485);
DISPLAY 0.617021 (440 4485);
PAINT ORANGE (440 4485);
FORCEPROP 2 LASTPROP $XRERR UNIQUE?
J 0
(200 4485);
DISPLAY 0.638298 (200 4485);
PAINT MONO (200 4485);
DISPLAY INVISIBLE (200 4485);
WIRE 16 -1 (-1375 4475)(-1375 4225);
WIRE 16 2175 (3100 3475)(3100 2425);
WIRE 16 2175 (2700 3475)(3100 3475);
WIRE 16 2175 (3100 2425)(2700 2425);
WIRE 16 2175 (2700 2425)(2700 3475);
WIRE 16 -1 (3050 3100)(3600 3100);
FORCEPROP 2 LAST SIG_NAME FM_CPU_ERR1_LVT3_N
J 0
(3125 3110);
DISPLAY 0.617021 (3125 3110);
PAINT ORANGE (3125 3110);
WIRE 16 -1 (3050 3350)(3600 3350);
FORCEPROP 2 LAST SIG_NAME FM_CPU_ERR0_LVT3_N
J 0
(3125 3360);
DISPLAY 0.617021 (3125 3360);
PAINT ORANGE (3125 3360);
WIRE 16 -1 (3050 2575)(3600 2575);
FORCEPROP 2 LAST SIG_NAME FM_CPU1_PROCHOT_LVT3_N
J 0
(3125 2585);
DISPLAY 0.617021 (3125 2585);
PAINT ORANGE (3125 2585);
WIRE 16 -1 (3050 2850)(3600 2850);
FORCEPROP 2 LAST SIG_NAME FM_CPU0_PROCHOT_LVT3_N
J 0
(3125 2860);
DISPLAY 0.617021 (3125 2860);
PAINT ORANGE (3125 2860);
WIRE 16 -1 (2400 3750)(2400 3350);
WIRE 16 -1 (2850 3350)(2400 3350);
WIRE 16 -1 (1975 3350)(2400 3350);
FORCEPROP 2 LAST SIG_NAME FM_CPU_ERR0_LVT3_K_N
J 0
(2090 3360);
DISPLAY 0.617021 (2090 3360);
PAINT ORANGE (2090 3360);
FORCEPROP 2 LASTPROP $XRERR UNIQUE?
J 0
(1850 3360);
DISPLAY 0.638298 (1850 3360);
PAINT MONO (1850 3360);
DISPLAY INVISIBLE (1850 3360);
WIRE 16 -1 (2400 2325)(2400 2575);
WIRE 16 -1 (2850 2575)(2400 2575);
WIRE 16 -1 (1975 2575)(2400 2575);
FORCEPROP 2 LAST SIG_NAME FM_CPU1_PROCHOT_LVT3_K_N
J 0
(2115 2585);
DISPLAY 0.617021 (2115 2585);
PAINT ORANGE (2115 2585);
FORCEPROP 2 LASTPROP $XRERR UNIQUE?
J 0
(1875 2585);
DISPLAY 0.638298 (1875 2585);
PAINT MONO (1875 2585);
DISPLAY INVISIBLE (1875 2585);
WIRE 16 -1 (2400 2125)(2400 1650);
WIRE 16 -1 (2400 1650)(-1400 1650);
FORCEPROP 2 LAST SIG_NAME H_CPU1_PROCHOT_G_PCH_N
J 0
(25 1660);
DISPLAY 0.617021 (25 1660);
PAINT ORANGE (25 1660);
FORCEPROP 2 LASTPROP $XRERR UNIQUE?
J 0
(-215 1660);
DISPLAY 0.638298 (-215 1660);
PAINT MONO (-215 1660);
DISPLAY INVISIBLE (-215 1660);
WIRE 16 -1 (-1400 1650)(-1400 1800);
WIRE 16 2175 (2600 2000)(2600 4075);
WIRE 16 2175 (1600 2000)(2600 2000);
WIRE 16 2175 (2600 4075)(1600 4075);
WIRE 16 2175 (1600 4075)(1600 2000);
WIRE 16 -1 (3700 525)(3700 650);
WIRE 16 -1 (3275 650)(3700 650);
FORCEPROP 2 LAST SIG_NAME PD_GTL2104_4_DIR
J 0
(3300 660);
DISPLAY 0.617021 (3300 660);
PAINT ORANGE (3300 660);
WIRE 16 -1 (2275 1000)(2275 775);
WIRE 16 -1 (2275 775)(2275 675);
WIRE 16 -1 (1925 775)(2275 775);
FORCEPROP 0 LAST VOLTAGE 0.734
J 0
(2100 825);
DISPLAY 1.021277 (2100 825);
PAINT SKYBLUE (2100 825);
DISPLAY INVISIBLE (2100 825);
WIRE 16 -1 (1925 725)(1925 775);
WIRE 16 -1 (1700 775)(1925 775);
FORCEPROP 2 LAST SIG_NAME P0V7_GTL2104_5_VREF
J 0
(1715 785);
DISPLAY 0.617021 (1715 785);
PAINT ORANGE (1715 785);
WIRE 16 -1 (1975 2850)(2025 2850);
WIRE 16 -1 (2850 2850)(2025 2850);
FORCEPROP 2 LAST SIG_NAME FM_CPU0_PROCHOT_LVT3_K_N
J 0
(2090 2860);
DISPLAY 0.617021 (2090 2860);
PAINT ORANGE (2090 2860);
FORCEPROP 2 LASTPROP $XRERR UNIQUE?
J 0
(1850 2860);
DISPLAY 0.638298 (1850 2860);
PAINT MONO (1850 2860);
DISPLAY INVISIBLE (1850 2860);
WIRE 16 -1 (2025 2325)(2025 2850);
WIRE 16 -1 (2025 3750)(2025 3100);
WIRE 16 -1 (2850 3100)(2025 3100);
FORCEPROP 2 LAST SIG_NAME FM_CPU_ERR1_LVT3_K_N
J 0
(2090 3110);
DISPLAY 0.617021 (2090 3110);
PAINT ORANGE (2090 3110);
FORCEPROP 2 LASTPROP $XRERR UNIQUE?
J 0
(1850 3110);
DISPLAY 0.638298 (1850 3110);
PAINT MONO (1850 3110);
DISPLAY INVISIBLE (1850 3110);
WIRE 16 -1 (1975 3100)(2025 3100);
WIRE 16 -1 (875 3300)(1725 3300);
FORCEPROP 2 LAST SIG_NAME FM_CPU_ERR1_LVT3_R_N
J 0
(1000 3310);
DISPLAY 0.617021 (1000 3310);
PAINT ORANGE (1000 3310);
FORCEPROP 2 LASTPROP $XRERR UNIQUE?
J 0
(760 3310);
DISPLAY 0.638298 (760 3310);
PAINT MONO (760 3310);
DISPLAY INVISIBLE (760 3310);
WIRE 16 -1 (1725 3300)(1725 3100);
WIRE 16 -1 (1725 3100)(1775 3100);
WIRE 16 -1 (1625 3200)(1625 2575);
WIRE 16 -1 (875 3200)(1625 3200);
FORCEPROP 2 LAST SIG_NAME FM_CPU1_PROCHOT_LVT3_R_N
J 0
(1000 3210);
DISPLAY 0.617021 (1000 3210);
PAINT ORANGE (1000 3210);
FORCEPROP 2 LASTPROP $XRERR UNIQUE?
J 0
(760 3210);
DISPLAY 0.638298 (760 3210);
PAINT MONO (760 3210);
DISPLAY INVISIBLE (760 3210);
WIRE 16 -1 (1625 2575)(1775 2575);
WIRE 16 -1 (1675 3250)(1675 2850);
WIRE 16 -1 (875 3250)(1675 3250);
FORCEPROP 2 LAST SIG_NAME FM_CPU0_PROCHOT_LVT3_R_N
J 0
(1000 3260);
DISPLAY 0.617021 (1000 3260);
PAINT ORANGE (1000 3260);
FORCEPROP 2 LASTPROP $XRERR UNIQUE?
J 0
(760 3260);
DISPLAY 0.638298 (760 3260);
PAINT MONO (760 3260);
DISPLAY INVISIBLE (760 3260);
WIRE 16 -1 (1675 2850)(1775 2850);
WIRE 16 -1 (875 3350)(1775 3350);
FORCEPROP 2 LAST SIG_NAME FM_CPU_ERR0_LVT3_R_N
J 0
(1000 3360);
DISPLAY 0.617021 (1000 3360);
PAINT ORANGE (1000 3360);
FORCEPROP 2 LASTPROP $XRERR UNIQUE?
J 0
(760 3360);
DISPLAY 0.638298 (760 3360);
PAINT MONO (760 3360);
DISPLAY INVISIBLE (760 3360);
WIRE 16 -1 (875 3600)(1425 3600);
FORCEPROP 0 LAST SIG_NAME P0V7_GTL2104_5_VREF
J 0
(975 3610);
DISPLAY 0.617021 (975 3610);
PAINT ORANGE (975 3610);
WIRE 16 -1 (875 3500)(1425 3500);
FORCEPROP 2 LAST SIG_NAME PD_GTL2104_4_DIR
J 0
(975 3510);
DISPLAY 0.617021 (975 3510);
PAINT ORANGE (975 3510);
WIRE 16 -1 (2025 2125)(2025 1700);
WIRE 16 -1 (-1100 1700)(2025 1700);
FORCEPROP 2 LAST SIG_NAME H_CPU0_PROCHOT_G_PCH_N
J 0
(25 1710);
DISPLAY 0.617021 (25 1710);
PAINT ORANGE (25 1710);
FORCEPROP 2 LASTPROP $XRERR UNIQUE?
J 0
(-215 1710);
DISPLAY 0.638298 (-215 1710);
PAINT MONO (-215 1710);
DISPLAY INVISIBLE (-215 1710);
WIRE 16 -1 (-1100 1800)(-1100 1700);
WIRE 16 -1 (925 1300)(925 1400);
WIRE 16 -1 (925 175)(925 1300);
WIRE 16 -1 (-450 1300)(925 1300);
WIRE 16 -1 (925 1400)(-125 1400);
WIRE 16 -1 (-450 1400)(-125 1400);
WIRE 16 -1 (-125 1400)(-125 175);
WIRE 16 -1 (-450 1300)(-450 1400);
WIRE 16 -1 (-450 175)(-450 1300);
WIRE 16 -1 (925 175)(-125 175);
WIRE 16 -1 (-450 175)(-125 175);
WIRE 16 2175 (-550 4350)(-1525 4350);
WIRE 16 2175 (-550 1750)(-550 4350);
WIRE 16 2175 (-1525 4350)(-1525 1750);
WIRE 16 2175 (-1525 1750)(-550 1750);
WIRE 16 2175 (-2975 4425)(-1700 4425);
WIRE 16 2175 (-2975 4425)(-2975 3000);
WIRE 16 2175 (-1700 3000)(-1700 4425);
WIRE 16 2175 (-2975 3000)(-1700 3000);
WIRE 16 -1 (-25 3200)(-625 3200);
FORCEPROP 2 LAST SIG_NAME H_CPU1_PROCHOT_G_R_N
J 0
(-575 3210);
DISPLAY 0.617021 (-575 3210);
PAINT ORANGE (-575 3210);
FORCEPROP 2 LASTPROP $XRERR UNIQUE?
J 0
(-815 3210);
DISPLAY 0.638298 (-815 3210);
PAINT MONO (-815 3210);
DISPLAY INVISIBLE (-815 3210);
WIRE 16 -1 (-625 3200)(-625 2175);
WIRE 16 -1 (-625 2175)(-725 2175);
WIRE 16 -1 (-25 3250)(-675 3250);
FORCEPROP 2 LAST SIG_NAME H_CPU0_PROCHOT_G_R_N
J 0
(-575 3260);
DISPLAY 0.617021 (-575 3260);
PAINT ORANGE (-575 3260);
FORCEPROP 2 LASTPROP $XRERR UNIQUE?
J 0
(-815 3260);
DISPLAY 0.638298 (-815 3260);
PAINT MONO (-815 3260);
DISPLAY INVISIBLE (-815 3260);
WIRE 16 -1 (-675 2300)(-675 3250);
WIRE 16 -1 (-725 2300)(-675 2300);
WIRE 16 -1 (-25 3350)(-775 3350);
FORCEPROP 2 LAST SIG_NAME H_CPU_ERR0_GTL_N
J 0
(-575 3360);
DISPLAY 0.617021 (-575 3360);
PAINT ORANGE (-575 3360);
FORCEPROP 2 LASTPROP $XRERR UNIQUE?
J 0
(-815 3360);
DISPLAY 0.638298 (-815 3360);
PAINT MONO (-815 3360);
DISPLAY INVISIBLE (-815 3360);
WIRE 16 -1 (-775 3825)(-775 3350);
WIRE 16 -1 (-825 3825)(-775 3825);
WIRE 16 -1 (-25 3300)(-825 3300);
FORCEPROP 2 LAST SIG_NAME H_CPU_ERR1_GTL_N
J 0
(-500 3310);
DISPLAY 0.617021 (-500 3310);
PAINT ORANGE (-500 3310);
FORCEPROP 2 LASTPROP $XRERR UNIQUE?
J 0
(-740 3310);
DISPLAY 0.638298 (-740 3310);
PAINT MONO (-740 3310);
DISPLAY INVISIBLE (-740 3310);
WIRE 16 -1 (-1100 2000)(-1100 2300);
WIRE 16 -1 (-925 2300)(-1100 2300);
WIRE 16 -1 (-1100 2300)(-2475 2300);
WIRE 16 -1 (-2475 2300)(-2475 2425);
WIRE 16 -1 (-2475 2300)(-2750 2300);
WIRE 16 -1 (-2750 2425)(-2750 2300);
FORCEPROP 2 LAST SIG_NAME H_CPU0_PROCHOT_G_N
J 0
(-3325 2311);
DISPLAY 0.617021 (-3325 2311);
PAINT ORANGE (-3325 2311);
WIRE 16 -1 (-3350 2300)(-2750 2300);
WIRE 16 -1 (-925 2175)(-1400 2175);
WIRE 16 -1 (-1400 2175)(-1900 2175);
WIRE 16 -1 (-1400 2000)(-1400 2175);
WIRE 16 -1 (-1900 2400)(-1900 2175);
WIRE 16 -1 (-1900 2175)(-2200 2175);
WIRE 16 -1 (-2200 2400)(-2200 2175);
WIRE 16 -1 (-3350 2175)(-2200 2175);
FORCEPROP 2 LAST SIG_NAME H_CPU1_PROCHOT_G_N
J 0
(-3325 2186);
DISPLAY 0.617021 (-3325 2186);
PAINT ORANGE (-3325 2186);
WIRE 16 -1 (-1375 4025)(-1375 3825);
WIRE 16 -1 (-1025 3825)(-1375 3825);
WIRE 16 -1 (-2325 3825)(-1375 3825);
WIRE 16 -1 (-2325 3950)(-2325 3825);
WIRE 16 -1 (-2475 3825)(-2325 3825);
FORCEPROP 0 LAST SIG_NAME H_CPU_ERR0_GTL_R_N
J 0
(-2275 3835);
DISPLAY 0.617021 (-2275 3835);
PAINT ORANGE (-2275 3835);
FORCEPROP 2 LASTPROP $XRERR UNIQUE?
J 0
(-2515 3835);
DISPLAY 0.638298 (-2515 3835);
PAINT MONO (-2515 3835);
DISPLAY INVISIBLE (-2515 3835);
WIRE 16 -1 (-2475 3975)(-2475 3825);
WIRE 16 -1 (-2475 3725)(-2475 3825);
WIRE 16 -1 (-2475 3725)(-2650 3725);
WIRE 16 -1 (-2650 3975)(-2475 3975);
WIRE 16 -1 (-1025 3300)(-1100 3300);
WIRE 16 -1 (-1100 4025)(-1100 3300);
WIRE 16 -1 (-2025 3300)(-1100 3300);
WIRE 16 -1 (-2025 3950)(-2025 3300);
WIRE 16 -1 (-2475 3300)(-2025 3300);
FORCEPROP 0 LAST SIG_NAME H_CPU_ERR1_GTL_R_N
J 0
(-2275 3310);
DISPLAY 0.617021 (-2275 3310);
PAINT ORANGE (-2275 3310);
FORCEPROP 2 LASTPROP $XRERR UNIQUE?
J 0
(-2515 3310);
DISPLAY 0.638298 (-2515 3310);
PAINT MONO (-2515 3310);
DISPLAY INVISIBLE (-2515 3310);
WIRE 16 -1 (-2475 3300)(-2475 3200);
WIRE 16 -1 (-2475 3300)(-2475 3425);
WIRE 16 -1 (-2475 3425)(-2650 3425);
WIRE 16 -1 (-2475 3200)(-2650 3200);
WIRE 16 2175 (-2900 2075)(-1625 2075);
WIRE 16 2175 (-2900 2925)(-2900 2075);
WIRE 16 2175 (-1625 2075)(-1625 2925);
WIRE 16 2175 (-2900 2925)(-1625 2925);
WIRE 16 -1 (-2125 1050)(-1375 1050);
FORCEPROP 2 LAST SIG_NAME FM_CPU_ERR1_LVT3_BMC_N
J 0
(-1975 1060);
DISPLAY 0.617021 (-1975 1060);
PAINT ORANGE (-1975 1060);
WIRE 16 -1 (-2125 850)(-1375 850);
FORCEPROP 2 LAST SIG_NAME FM_CPU_ERR1_PCH_N
J 0
(-1975 860);
DISPLAY 0.617021 (-1975 860);
PAINT ORANGE (-1975 860);
WIRE 16 2175 (-2475 1625)(-1975 1625);
WIRE 16 2175 (-2475 -50)(-2475 1625);
WIRE 16 2175 (-1975 1625)(-1975 -50);
WIRE 16 2175 (-1975 -50)(-2475 -50);
WIRE 16 -1 (-2125 675)(-1375 675);
FORCEPROP 2 LAST SIG_NAME FM_CPU0_PROCHOT_LVT3_BMC_N
J 0
(-1975 685);
DISPLAY 0.617021 (-1975 685);
PAINT ORANGE (-1975 685);
WIRE 16 -1 (-2125 275)(-1375 275);
FORCEPROP 2 LAST SIG_NAME FM_CPU1_PROCHOT_LVT3_BMC_N
J 0
(-1975 285);
DISPLAY 0.617021 (-1975 285);
PAINT ORANGE (-1975 285);
WIRE 16 -1 (-2125 1250)(-1375 1250);
FORCEPROP 2 LAST SIG_NAME FM_CPU_ERR0_PCH_N
J 0
(-1975 1260);
DISPLAY 0.617021 (-1975 1260);
PAINT ORANGE (-1975 1260);
WIRE 16 -1 (-2125 475)(-1375 475);
FORCEPROP 2 LAST SIG_NAME FM_CPU0_PROCHOT_PCH_N
J 0
(-1975 485);
DISPLAY 0.617021 (-1975 485);
PAINT ORANGE (-1975 485);
WIRE 16 -1 (-2125 75)(-1375 75);
FORCEPROP 2 LAST SIG_NAME FM_CPU1_PROCHOT_PCH_N
J 0
(-1975 85);
DISPLAY 0.617021 (-1975 85);
PAINT ORANGE (-1975 85);
WIRE 16 -1 (-2125 1450)(-1375 1450);
FORCEPROP 2 LAST SIG_NAME FM_CPU_ERR0_LVT3_BMC_N
J 0
(-1975 1460);
DISPLAY 0.617021 (-1975 1460);
PAINT ORANGE (-1975 1460);
WIRE 16 -1 (-3350 3975)(-2850 3975);
FORCEPROP 2 LAST SIG_NAME H_CPU0_ERR0_G_N
J 0
(-3325 3985);
DISPLAY 0.617021 (-3325 3985);
PAINT ORANGE (-3325 3985);
WIRE 16 -1 (-3350 3200)(-2850 3200);
FORCEPROP 2 LAST SIG_NAME H_CPU1_ERR1_G_N
J 0
(-3325 3210);
DISPLAY 0.617021 (-3325 3210);
PAINT ORANGE (-3325 3210);
WIRE 16 -1 (-3350 3725)(-2850 3725);
FORCEPROP 2 LAST SIG_NAME H_CPU1_ERR0_G_N
J 0
(-3325 3735);
DISPLAY 0.617021 (-3325 3735);
PAINT ORANGE (-3325 3735);
WIRE 16 -1 (-3350 3425)(-2850 3425);
FORCEPROP 2 LAST SIG_NAME H_CPU0_ERR1_G_N
J 0
(-3325 3435);
DISPLAY 0.617021 (-3325 3435);
PAINT ORANGE (-3325 3435);
WIRE 16 -1 (-2550 1450)(-2325 1450);
WIRE 16 -1 (-2550 1250)(-2550 1450);
WIRE 16 -1 (-3125 1450)(-2550 1450);
FORCEPROP 2 LAST SIG_NAME FM_CPU_ERR0_LVT3_N
J 0
(-3100 1460);
DISPLAY 0.617021 (-3100 1460);
PAINT ORANGE (-3100 1460);
WIRE 16 -1 (-2325 1250)(-2550 1250);
WIRE 16 -1 (-2550 1050)(-2325 1050);
WIRE 16 -1 (-2550 850)(-2550 1050);
WIRE 16 -1 (-3125 1050)(-2550 1050);
FORCEPROP 2 LAST SIG_NAME FM_CPU_ERR1_LVT3_N
J 0
(-3100 1060);
DISPLAY 0.617021 (-3100 1060);
PAINT ORANGE (-3100 1060);
WIRE 16 -1 (-2325 850)(-2550 850);
WIRE 16 -1 (-2550 675)(-2325 675);
WIRE 16 -1 (-2550 475)(-2550 675);
WIRE 16 -1 (-3125 675)(-2550 675);
FORCEPROP 2 LAST SIG_NAME FM_CPU0_PROCHOT_LVT3_N
J 0
(-3100 685);
DISPLAY 0.617021 (-3100 685);
PAINT ORANGE (-3100 685);
WIRE 16 -1 (-2325 475)(-2550 475);
WIRE 16 -1 (-2550 275)(-2325 275);
WIRE 16 -1 (-2550 75)(-2550 275);
WIRE 16 -1 (-3125 275)(-2550 275);
FORCEPROP 2 LAST SIG_NAME FM_CPU1_PROCHOT_LVT3_N
J 0
(-3100 285);
DISPLAY 0.617021 (-3100 285);
PAINT ORANGE (-3100 285);
WIRE 16 -1 (-2325 75)(-2550 75);
DOT 1 (2400 3350);
DOT 1 (2400 2575);
DOT 1 (2275 775);
DOT 1 (2275 325);
DOT 1 (2025 3100);
DOT 1 (2025 2850);
DOT 1 (1000 4050);
DOT 1 (1925 775);
DOT 1 (925 1300);
DOT 1 (-2325 4225);
DOT 1 (-200 3000);
DOT 1 (-200 2950);
DOT 1 (-1375 3825);
DOT 1 (-1100 3300);
DOT 1 (-2025 3300);
DOT 1 (-1100 2300);
DOT 1 (-1400 2175);
DOT 1 (-1900 2175);
DOT 1 (-125 1400);
DOT 1 (-450 1300);
DOT 1 (-125 175);
DOT 1 (-2325 3825);
DOT 1 (-2475 3825);
DOT 1 (-2475 3300);
DOT 1 (-2200 2700);
DOT 1 (-2200 2175);
DOT 1 (-2475 2300);
DOT 1 (-2750 2725);
DOT 1 (-2750 2300);
DOT 1 (-2550 1450);
DOT 1 (-2550 1050);
DOT 1 (-2550 675);
DOT 1 (-2550 275);
FORCENOTE
IE ONLY (NO BMC)
(-425 1425) 0;
DISPLAY LEFT (-425 1425);
DISPLAY 1.021277 (-425 1425);
PAINT PURPLE (-425 1425);
FORCENOTE
R1T35
(-75 475) 0;
DISPLAY LEFT (-75 475);
DISPLAY 1.021277 (-75 475);
PAINT PURPLE (-75 475);
FORCENOTE
WITH 20 OHM RESISTOR G21976-173
(-75 225) 0;
DISPLAY LEFT (-75 225);
DISPLAY 1.021277 (-75 225);
PAINT PURPLE (-75 225);
FORCENOTE
R8F37
(-75 625) 0;
DISPLAY LEFT (-75 625);
DISPLAY 1.021277 (-75 625);
PAINT PURPLE (-75 625);
FORCENOTE
STUFF R2T17, R2T20, R2T32, & R2T27
(-75 300) 0;
DISPLAY LEFT (-75 300);
DISPLAY 1.021277 (-75 300);
PAINT PURPLE (-75 300);
FORCENOTE
R2T63
(-75 550) 0;
DISPLAY LEFT (-75 550);
DISPLAY 1.021277 (-75 550);
PAINT PURPLE (-75 550);
FORCENOTE
R2T70
(-75 775) 0;
DISPLAY LEFT (-75 775);
DISPLAY 1.021277 (-75 775);
PAINT PURPLE (-75 775);
FORCENOTE
R1T38
(-75 400) 0;
DISPLAY LEFT (-75 400);
DISPLAY 1.021277 (-75 400);
PAINT PURPLE (-75 400);
FORCENOTE
R2T71
(-75 850) 0;
DISPLAY LEFT (-75 850);
DISPLAY 1.021277 (-75 850);
PAINT PURPLE (-75 850);
FORCENOTE
R2T69
(-75 1150) 0;
DISPLAY LEFT (-75 1150);
DISPLAY 1.021277 (-75 1150);
PAINT PURPLE (-75 1150);
FORCENOTE
R2T57
(-75 1225) 0;
DISPLAY LEFT (-75 1225);
DISPLAY 1.021277 (-75 1225);
PAINT PURPLE (-75 1225);
FORCENOTE
STUFF
(-75 1325) 0;
DISPLAY LEFT (-75 1325);
DISPLAY 1.021277 (-75 1325);
PAINT PURPLE (-75 1325);
FORCENOTE
R2T61
(-75 1075) 0;
DISPLAY LEFT (-75 1075);
DISPLAY 1.021277 (-75 1075);
PAINT PURPLE (-75 1075);
FORCENOTE
R2T59
(-75 1000) 0;
DISPLAY LEFT (-75 1000);
DISPLAY 1.021277 (-75 1000);
PAINT PURPLE (-75 1000);
FORCENOTE
R2T62
(-75 925) 0;
DISPLAY LEFT (-75 925);
DISPLAY 1.021277 (-75 925);
PAINT PURPLE (-75 925);
FORCENOTE
R2T58
(-75 700) 0;
DISPLAY LEFT (-75 700);
DISPLAY 1.021277 (-75 700);
PAINT PURPLE (-75 700);
FORCENOTE
R2T31
(-400 1075) 0;
DISPLAY LEFT (-400 1075);
DISPLAY 1.021277 (-400 1075);
PAINT PURPLE (-400 1075);
FORCENOTE
R2T16
(-400 1150) 0;
DISPLAY LEFT (-400 1150);
DISPLAY 1.021277 (-400 1150);
PAINT PURPLE (-400 1150);
FORCENOTE
UNSTUFF
(-425 1325) 0;
DISPLAY LEFT (-425 1325);
DISPLAY 1.021277 (-425 1325);
PAINT PURPLE (-425 1325);
FORCENOTE
U2T4
(-400 1225) 0;
DISPLAY LEFT (-400 1225);
DISPLAY 1.021277 (-400 1225);
PAINT PURPLE (-400 1225);
FORCENOTE
R2T60
(-400 1000) 0;
DISPLAY LEFT (-400 1000);
DISPLAY 1.021277 (-400 1000);
PAINT PURPLE (-400 1000);
FORCENOTE
R2T65
(-400 850) 0;
DISPLAY LEFT (-400 850);
DISPLAY 1.021277 (-400 850);
PAINT PURPLE (-400 850);
FORCENOTE
R2T66
(-400 775) 0;
DISPLAY LEFT (-400 775);
DISPLAY 1.021277 (-400 775);
PAINT PURPLE (-400 775);
FORCENOTE
R2T67
(-400 700) 0;
DISPLAY LEFT (-400 700);
DISPLAY 1.021277 (-400 700);
PAINT PURPLE (-400 700);
FORCENOTE
R7D41
(-400 625) 0;
DISPLAY LEFT (-400 625);
DISPLAY 1.021277 (-400 625);
PAINT PURPLE (-400 625);
FORCENOTE
R8F38
(-400 550) 0;
DISPLAY LEFT (-400 550);
DISPLAY 1.021277 (-400 550);
PAINT PURPLE (-400 550);
FORCENOTE
R2T68
(-400 925) 0;
DISPLAY LEFT (-400 925);
DISPLAY 1.021277 (-400 925);
PAINT PURPLE (-400 925);
FORCENOTE
R2T64
(-400 475) 0;
DISPLAY LEFT (-400 475);
DISPLAY 1.021277 (-400 475);
PAINT PURPLE (-400 475);
FORCENOTE
R1T37
(-400 325) 0;
DISPLAY LEFT (-400 325);
DISPLAY 1.021277 (-400 325);
PAINT PURPLE (-400 325);
FORCENOTE
R1T36
(-400 400) 0;
DISPLAY LEFT (-400 400);
DISPLAY 1.021277 (-400 400);
PAINT PURPLE (-400 400);
FORCENOTE
ROOM=PROC_SIDEBAND
(-3721 -157) 0;
DISPLAY LEFT (-3721 -157);
DISPLAY 1.595745 (-3721 -157);
PAINT PURPLE (-3721 -157);
QUIT
